# Altium SchDoc records: 05-GPS_IMU_SENSORS.SchDoc
|HEADER=Protel for Windows - Schematic Capture Binary File Version 5.0|Weight=3224|MinorVersion=9
|RECORD=31|FontIdCount=10|Size1=10|FontName1=Times New Roman|Size2=10|Rotation2=90|FontName2=Times New Roman|Size3=10|Underline3=T|FontName3=Times New Roman|Size4=8|FontName4=Arial|Size5=10|FontName5=Arial|Size6=12|Underline6=T|FontName6=Arial|Size7=11|FontName7=Arial|Size8=24|FontName8=Times New Roman|Size9=12|FontName9=Arial|Size10=8|FontName10=Times New Roman|UseMBCS=T|IsBOC=T|HotSpotGridOn=T|HotSpotGridSize=4|SheetStyle=12|SystemFont=5|BorderOn=T|SheetNumberSpaceSize=12|AreaColor=16317695|SnapGridOn=T|SnapGridSize=10|VisibleGridOn=T|VisibleGridSize=10|CustomX=2338|CustomX_Frac=58268|CustomY=1653|CustomY_Frac=54331|CustomXZones=8|CustomYZones=6|CustomMarginWidth=19|CustomMarginWidth_Frac=80000|ShowTemplateGraphics=T|TemplateFileName=C:\Users\<user>\Documents\Altium\AD20\Templates\Timecard.SchDot|Display_Unit=0
|RECORD=39|IsNotAccesible=T|OwnerPartId=-1|FileName=C:\Users\<user>\Documents\Altium\AD20\Templates\Timecard.SchDot
|RECORD=4|OwnerIndex=1|OwnerPartId=-1|Location.X=1594|Location.Y=39|Color=8388608|FontID=6|Text=timingcard.com|URL=http://timingcard.com
|RECORD=6|OwnerIndex=1|IndexInSheet=1|OwnerPartId=-1|LocationCount=2|X1=1680|Y1=35|X2=1576|Y2=35
|RECORD=4|OwnerIndex=1|IndexInSheet=2|OwnerPartId=-1|Location.X=1615|Location.Y=27|Justification=4|Color=16711680|FontID=7|Text==SheetNumber
|RECORD=4|OwnerIndex=1|IndexInSheet=3|OwnerPartId=-1|Location.X=1581|Location.X_Frac=42446|Location.Y=29|Location.Y_Frac=96838|Justification=3|FontID=4|Text=SHEET
|RECORD=4|OwnerIndex=1|IndexInSheet=4|OwnerPartId=-1|Location.X=1639|Location.X_Frac=42446|Location.Y=29|Location.Y_Frac=96838|Justification=3|FontID=4|Text=OF
|RECORD=6|OwnerIndex=1|IndexInSheet=5|OwnerPartId=-1|LineWidth=1|LocationCount=2|X1=1679|X1_Frac=42446|Y1=117|Y1_Frac=96838|X2=1576|Y2=118
|RECORD=4|OwnerIndex=1|IndexInSheet=6|OwnerPartId=-1|Location.X=1659|Location.Y=27|Justification=4|Color=16711680|FontID=7|Text==SheetTotal
|RECORD=30|OwnerIndex=1|IndexInSheet=7|OwnerPartId=-1|Location.X=1578|Location.Y=65|Corner.X=1673|Corner.X_Frac=88801|Corner.Y=115|KeepAspect=T|FileName=C:\Users\<user>\Desktop\Timecard Logo\TIMECARD.jpg
|RECORD=6|OwnerIndex=1|IndexInSheet=8|OwnerPartId=-1|LineWidth=1|LocationCount=2|X1=1576|X1_Frac=3162|Y1=117|Y1_Frac=42446|X2=1576|Y2=21
|RECORD=6|OwnerIndex=1|IndexInSheet=9|OwnerPartId=-1|LocationCount=2|X1=1680|Y1=51|X2=1576|Y2=51
|RECORD=4|OwnerIndex=1|IndexInSheet=10|OwnerPartId=-1|Location.X=1581|Location.X_Frac=42446|Location.Y=56|Location.Y_Frac=96838|Justification=3|FontID=4|Text=REV
|RECORD=4|OwnerIndex=1|IndexInSheet=11|OwnerPartId=-1|Location.X=1619|Location.Y=57|Justification=3|FontID=4|Text=DATE
|RECORD=6|OwnerIndex=1|IndexInSheet=12|OwnerPartId=-1|LocationCount=2|X1=1680|Y1=65|X2=1576|Y2=65
|RECORD=4|OwnerIndex=1|IndexInSheet=13|OwnerPartId=-1|Location.X=1605|Location.Y=58|Justification=4|Color=16711680|FontID=7|Text==ProjectRevision
|RECORD=4|OwnerIndex=1|IndexInSheet=14|OwnerPartId=-1|Location.X=1659|Location.Y=58|Justification=4|Color=16711680|FontID=7|Text==ProjectDate
|RECORD=41|IndexInSheet=1|OwnerPartId=-1|Location.X=21474|Location.X_Frac=83647|Location.Y=21464|Location.Y_Frac=83647|Color=8388608|FontID=1|IsHidden=T|Text=01910|Name=Customer
|RECORD=41|IndexInSheet=2|OwnerPartId=-1|Location.X=1000|Location.Y=10|Color=8388608|FontID=1|IsHidden=T|Text=*|Name=DocStatus
|RECORD=17|IndexInSheet=3|OwnerPartId=-1|ShowNetName=T|Location.X=290|Location.Y=880|Orientation=1|Color=128|FontID=1|Text=+5.0V
|RECORD=17|IndexInSheet=4|OwnerPartId=-1|Style=4|ShowNetName=T|Location.X=710|Location.Y=790|Orientation=3|Color=128|FontID=1|Text=GND
|RECORD=17|IndexInSheet=5|OwnerPartId=-1|ShowNetName=T|Location.X=190|Location.Y=880|Orientation=1|Color=128|FontID=1|Text=+3.3V
|RECORD=17|IndexInSheet=6|OwnerPartId=-1|Style=4|ShowNetName=T|Location.X=190|Location.Y=800|Orientation=3|Color=128|FontID=1|Text=GND
|RECORD=17|IndexInSheet=7|OwnerPartId=-1|Style=4|ShowNetName=T|Location.X=290|Location.Y=800|Orientation=3|Color=128|FontID=1|Text=GND
|RECORD=17|IndexInSheet=8|OwnerPartId=-1|ShowNetName=T|Location.X=780|Location.Y=850|Color=255|FontID=1|Text=RCB_GPS1_TP2|IsCrossSheetConnector=T
|RECORD=17|IndexInSheet=9|OwnerPartId=-1|ShowNetName=T|Location.X=780|Location.Y=840|Color=255|FontID=1|Text=RCB_GPS1_TP1|IsCrossSheetConnector=T
|RECORD=17|IndexInSheet=10|OwnerPartId=-1|ShowNetName=T|Location.X=780|Location.Y=830|Color=255|FontID=1|Text=RCB_GPS1_RX|IsCrossSheetConnector=T
|RECORD=17|IndexInSheet=11|OwnerPartId=-1|ShowNetName=T|Location.X=440|Location.Y=840|Orientation=2|Color=255|FontID=1|Text=RCB_GPS1_TX|IsCrossSheetConnector=T
|RECORD=17|IndexInSheet=12|OwnerPartId=-1|ShowNetName=T|Location.X=440|Location.Y=830|Orientation=2|Color=255|FontID=1|Text=GPS1_RST|IsCrossSheetConnector=T
|RECORD=4|IndexInSheet=13|OwnerPartId=-1|Location.X=580|Location.Y=1050|Color=8388608|FontID=8|Text=GPS
|RECORD=1|LibReference=RCB-F9T|ComponentDescription=MOD, GPS|PartCount=2|DisplayModeCount=1|IndexInSheet=14|OwnerPartId=-1|Location.X=610|Location.Y=850|CurrentPartId=1|LibraryPath=*|SourceLibraryName=Modules.IntLib|TargetFileName=*|AreaColor=11599871|Color=128|PartIDLocked=F|PinsMoveable=T|DesignItemId=RCB-F9T|AllPinCount=8
|RECORD=41|OwnerIndex=30|OwnerPartId=-1|Location.X=610|Location.Y=850|Color=8388608|FontID=9|IsHidden=T|Text=RCB-F9T|Name=MFG PART NUM
|RECORD=41|OwnerIndex=30|IndexInSheet=1|OwnerPartId=-1|Location.X=610|Location.Y=850|Color=8388608|FontID=9|IsHidden=T|Text=UBLOCKS|Name=MFG NAME
|RECORD=41|OwnerIndex=30|IndexInSheet=2|OwnerPartId=-1|Location.X=610|Location.Y=850|Color=8388608|FontID=9|IsHidden=T|Text=MOD|Name=CATEGORY
|RECORD=41|OwnerIndex=30|IndexInSheet=3|OwnerPartId=-1|Location.X=610|Location.Y=850|Color=8388608|FontID=9|IsHidden=T|Text=9/11/13|Name=MODIFY DATE
|RECORD=41|OwnerIndex=30|IndexInSheet=4|OwnerPartId=-1|Location.X=608|Location.Y=599|Color=8388608|FontID=1|IsHidden=T|Text=GPS|Name=P1
|RECORD=41|OwnerIndex=30|IndexInSheet=5|OwnerPartId=-1|Location.X=608|Location.Y=599|Color=8388608|FontID=1|IsHidden=T|Name=P2
|RECORD=41|OwnerIndex=30|IndexInSheet=6|OwnerPartId=-1|Location.X=608|Location.Y=599|Color=8388608|FontID=1|IsHidden=T|Name=P3
|RECORD=41|OwnerIndex=30|IndexInSheet=7|OwnerPartId=-1|Location.X=608|Location.Y=599|Color=8388608|FontID=1|IsHidden=T|Name=OTHER
|RECORD=41|OwnerIndex=30|IndexInSheet=8|OwnerPartId=-1|Location.X=608|Location.Y=599|Color=8388608|FontID=1|IsHidden=T|Name=DATE
|RECORD=41|OwnerIndex=30|IndexInSheet=9|OwnerPartId=-1|Location.X=608|Location.Y=599|Color=8388608|FontID=1|IsHidden=T|Text=*|Name=SHEETPART
|RECORD=41|OwnerIndex=30|IndexInSheet=10|OwnerPartId=-1|Location.X=608|Location.Y=599|Color=8388608|FontID=1|IsHidden=T|Name=SUB
|RECORD=41|OwnerIndex=30|IndexInSheet=11|OwnerPartId=-1|Location.X=608|Location.Y=599|Color=8388608|FontID=1|IsHidden=T|Name=SIZE
|RECORD=41|OwnerIndex=30|IndexInSheet=12|OwnerPartId=-1|Location.X=608|Location.Y=599|Color=8388608|FontID=1|IsHidden=T|Text=-40C|Name=MINTEMP
|RECORD=41|OwnerIndex=30|IndexInSheet=13|OwnerPartId=-1|Location.X=608|Location.Y=599|Color=8388608|FontID=1|IsHidden=T|Text=80C|Name=MAXTEMP
|RECORD=41|OwnerIndex=30|IndexInSheet=14|OwnerPartId=-1|Location.X=608|Location.Y=589|Color=8388608|FontID=1|IsHidden=T|Text=.|Name=DATE
|RECORD=41|OwnerIndex=30|IndexInSheet=15|OwnerPartId=-1|Location.X=608|Location.Y=904|Color=8388608|FontID=1|IsHidden=T|Text=MOD BLE 4.2|Name=DESC
|RECORD=41|OwnerIndex=30|IndexInSheet=16|OwnerPartId=-1|Location.X=578|Location.Y=922|Color=8388608|FontID=1|IsHidden=T|Text=<V PART NUM>|Name=VELENTIUM PART NUM
|RECORD=41|OwnerIndex=30|IndexInSheet=17|OwnerPartId=-1|Location.X=528|Location.Y=904|Color=8388608|FontID=1|IsHidden=T|Text=Digi-Key|Name=Supplier 1|ReadOnlyState=3
|RECORD=41|OwnerIndex=30|IndexInSheet=18|OwnerPartId=-1|Location.X=528|Location.Y=904|Color=8388608|FontID=1|IsHidden=T|Text=672-RCB-F9T-ND|Name=Supplier Part Number 1|ReadOnlyState=3
|RECORD=14|OwnerIndex=30|IsNotAccesible=T|IndexInSheet=19|OwnerPartId=1|Location.X=560|Location.Y=820|Corner.X=660|Corner.Y=870|Color=128|AreaColor=11599871|IsSolid=T
|RECORD=2|OwnerIndex=30|OwnerPartId=1|FormalType=1|Electrical=4|PinConglomerate=26|PinLength=30|Location.X=560|Location.Y=860|Name=VCC_ANT|Designator=1|SwapIDPart=Ž&Ž||PinPropagationDelay=0.000000E+000
|RECORD=2|OwnerIndex=30|OwnerPartId=1|FormalType=1|Electrical=4|PinConglomerate=26|PinLength=30|Location.X=560|Location.Y=850|Name=VCC|Designator=2|SwapIDPart=Ž&Ž||PinPropagationDelay=0.000000E+000
|RECORD=2|OwnerIndex=30|OwnerPartId=1|FormalType=1|Electrical=4|PinConglomerate=26|PinLength=30|Location.X=560|Location.Y=840|Name=TXD|Designator=3|SwapIDPart=Ž&Ž||PinPropagationDelay=0.000000E+000
|RECORD=2|OwnerIndex=30|OwnerPartId=1|FormalType=1|Electrical=4|PinConglomerate=26|PinLength=30|Location.X=560|Location.Y=830|Name=RST|Designator=4|SwapIDPart=Ž&Ž||PinPropagationDelay=0.000000E+000
|RECORD=2|OwnerIndex=30|OwnerPartId=1|FormalType=1|Electrical=4|PinConglomerate=24|PinLength=30|Location.X=660|Location.Y=830|Name=RXD|Designator=5|SwapIDPart=Ž&Ž||PinPropagationDelay=0.000000E+000
|RECORD=2|OwnerIndex=30|OwnerPartId=1|FormalType=1|Electrical=4|PinConglomerate=24|PinLength=30|Location.X=660|Location.Y=840|Name=TP1|Designator=6|SwapIDPart=Ž&Ž||PinPropagationDelay=0.000000E+000
|RECORD=2|OwnerIndex=30|OwnerPartId=1|FormalType=1|Electrical=4|PinConglomerate=24|PinLength=30|Location.X=660|Location.Y=850|Name=TP2|Designator=7|SwapIDPart=Ž&Ž||PinPropagationDelay=0.000000E+000
|RECORD=2|OwnerIndex=30|OwnerPartId=1|FormalType=1|Electrical=4|PinConglomerate=24|PinLength=30|Location.X=660|Location.Y=860|Name=GND|Designator=8|SwapIDPart=Ž&Ž||PinPropagationDelay=0.000000E+000
|RECORD=34|OwnerIndex=30|IndexInSheet=-1|OwnerPartId=-1|Location.X=560|Location.Y=870|Color=8388608|FontID=1|Text=U9|Name=Designator|ReadOnlyState=1
|RECORD=41|OwnerIndex=30|IndexInSheet=-1|OwnerPartId=-1|Location.X=560|Location.Y=808|Color=8388608|FontID=1|Text=RCB-F9T|Name=Comment
|RECORD=44|OwnerIndex=30
|RECORD=45|OwnerIndex=69|IndexInSheet=-1|ModelName=GNSS|ModelType=PCBLIB|DatafileCount=1|ModelDatafileEntity0=GNSS|ModelDatafileKind0=PCBLib|IsCurrent=T|IntegratedModel=T|DatabaseModel=T
|RECORD=46|OwnerIndex=70
|RECORD=48|OwnerIndex=70
|RECORD=1|LibReference=93fe34f5f049140596bab6421a6454b|ComponentDescription=IC EEPROM 2K I2C 1MHZ SOT23-5|PartCount=2|DisplayModeCount=1|IndexInSheet=15|OwnerPartId=-1|Location.X=1450|Location.Y=810|CurrentPartId=1|LibraryPath=*|SourceLibraryName=Altium Content Vault|TargetFileName=*|AreaColor=11599871|Color=128|PartIDLocked=T|DesignItemId=CMP-06313-000011-1|AllPinCount=5
|RECORD=14|OwnerIndex=73|IsNotAccesible=T|OwnerPartId=1|Location.X=1470|Location.Y=760|Corner.X=1540|Corner.Y=820|LineWidth=1|Color=128|AreaColor=11599871|IsSolid=T
|RECORD=2|OwnerIndex=73|OwnerPartId=1|Electrical=7|PinConglomerate=58|PinLength=20|Location.X=1470|Location.Y=810|Name=VCC|Designator=4|PinPropagationDelay=0.000000E+000
|RECORD=2|OwnerIndex=73|OwnerPartId=1|SymBol_InnerEdge=3|PinConglomerate=56|PinLength=20|Location.X=1540|Location.Y=810|Name=SCL|Designator=1|PinPropagationDelay=0.000000E+000
|RECORD=2|OwnerIndex=73|OwnerPartId=1|Electrical=1|PinConglomerate=56|PinLength=20|Location.X=1540|Location.Y=800|Name=SDA|Designator=3|PinPropagationDelay=0.000000E+000
|RECORD=2|OwnerIndex=73|OwnerPartId=1|PinConglomerate=58|PinLength=20|Location.X=1470|Location.Y=770|Name=WP|Designator=5|PinPropagationDelay=0.000000E+000
|RECORD=2|OwnerIndex=73|OwnerPartId=1|Electrical=7|PinConglomerate=56|PinLength=20|Location.X=1540|Location.Y=770|Name=GND|Designator=2|PinPropagationDelay=0.000000E+000
|RECORD=41|OwnerIndex=73|IndexInSheet=6|OwnerPartId=-1|Location.X=1448|Location.Y=820|Color=8388608|FontID=1|IsHidden=T|Text=-40°C|Name=Temperature Range Low
|RECORD=41|OwnerIndex=73|IndexInSheet=7|OwnerPartId=-1|Location.X=1448|Location.Y=820|Color=8388608|FontID=1|IsHidden=T|Text=1mm|Name=Height
|RECORD=41|OwnerIndex=73|IndexInSheet=8|OwnerPartId=-1|Location.X=1448|Location.Y=820|Color=8388608|FontID=3|IsHidden=T|Text=http://ww1.microchip.com/downloads/en/DeviceDoc/Atmel-8807-SEEPROM-AT24MAC402-602-Datasheet.pdf|Name=ComponentLink2URL
|RECORD=41|OwnerIndex=73|IndexInSheet=9|OwnerPartId=-1|Location.X=1448|Location.Y=820|Color=8388608|FontID=1|IsHidden=T|Text=SOT95P280X100-5|Name=Ipc Land Pattern Name
|RECORD=41|OwnerIndex=73|IndexInSheet=10|OwnerPartId=-1|Location.X=1448|Location.Y=820|Color=8388608|FontID=1|IsHidden=T|Text=2Kbits|Name=Memory Size
|RECORD=41|OwnerIndex=73|IndexInSheet=11|OwnerPartId=-1|Location.X=1448|Location.Y=820|Color=8388608|FontID=1|IsHidden=T|Text=IC|Name=Category
|RECORD=41|OwnerIndex=73|IndexInSheet=12|OwnerPartId=-1|Location.X=1448|Location.Y=820|Color=8388608|FontID=1|IsHidden=T|Text=EEPROM|Name=Memory Type
|RECORD=41|OwnerIndex=73|IndexInSheet=13|OwnerPartId=-1|Location.X=1448|Location.Y=820|Color=8388608|FontID=1|IsHidden=T|Text=IC EEPROM 2K I2C 1MHZ SOT23-5|Name=Digikey Description
|RECORD=41|OwnerIndex=73|IndexInSheet=14|OwnerPartId=-1|Location.X=1448|Location.Y=820|Color=8388608|FontID=1|IsHidden=T|Text=1.7V|Name=Min Supply Voltage
|RECORD=41|OwnerIndex=73|IndexInSheet=15|OwnerPartId=-1|Location.X=1448|Location.Y=820|Color=8388608|FontID=1|IsHidden=T|Text=AT24MAC402-STUM-T|Name=Manufacturer Part Number
|RECORD=41|OwnerIndex=73|IndexInSheet=16|OwnerPartId=-1|Location.X=1448|Location.Y=820|Color=8388608|FontID=1|IsHidden=T|Text=Integrated Circuits (ICs)|Name=Device Class L1
|RECORD=41|OwnerIndex=73|IndexInSheet=17|OwnerPartId=-1|Location.X=1448|Location.Y=820|Color=8388608|FontID=1|IsHidden=T|Text=+85°C|Name=Temperature Range High
|RECORD=41|OwnerIndex=73|IndexInSheet=18|OwnerPartId=-1|Location.X=1448|Location.Y=820|Color=8388608|FontID=1|IsHidden=T|Text=Datasheet|Name=ComponentLink2Description
|RECORD=41|OwnerIndex=73|IndexInSheet=19|OwnerPartId=-1|Location.X=1448|Location.Y=820|Color=8388608|FontID=1|IsHidden=T|Text=5.5V|Name=Max Supply Voltage
|RECORD=41|OwnerIndex=73|IndexInSheet=20|OwnerPartId=-1|Location.X=1448|Location.Y=820|Color=8388608|FontID=1|IsHidden=T|Text=TRUE|Name=RoHS
|RECORD=41|OwnerIndex=73|IndexInSheet=21|OwnerPartId=-1|Location.X=1448|Location.Y=820|Color=8388608|FontID=1|IsHidden=T|Text=1000kHz|Name=Frequency
|RECORD=41|OwnerIndex=73|IndexInSheet=22|OwnerPartId=-1|Location.X=1448|Location.Y=820|Color=8388608|FontID=1|IsHidden=T|Text=EEPROM Serial-I2C 2K-bit 256 x 8 1.8V/2.5V/3.3V/5V 5-Pin SOT-23 T/R|Name=Mouser Description
|RECORD=41|OwnerIndex=73|IndexInSheet=23|OwnerPartId=-1|Location.X=1448|Location.Y=820|Color=8388608|FontID=1|IsHidden=T|Text=Microchip|Name=Manufacturer
|RECORD=41|OwnerIndex=73|IndexInSheet=24|OwnerPartId=-1|Location.X=1448|Location.Y=820|Color=8388608|FontID=1|IsHidden=T|Text=0mm|Name=Standoff Height
|RECORD=41|OwnerIndex=73|IndexInSheet=25|OwnerPartId=-1|Location.X=1448|Location.Y=820|Color=8388608|FontID=3|IsHidden=T|Text=https://octopart.com/at24mac402-stum-t-microchip-77758112|Name=Octopart
|RECORD=41|OwnerIndex=73|IndexInSheet=26|OwnerPartId=-1|Location.X=1448|Location.Y=820|Color=8388608|FontID=1|IsHidden=T|Text=0.4-2mA|Name=Nominal Supply Current
|RECORD=41|OwnerIndex=73|IndexInSheet=27|OwnerPartId=-1|Location.X=1448|Location.Y=820|Color=8388608|FontID=1|IsHidden=T|Text=-40°C to +85°C|Name=Temperature
|RECORD=41|OwnerIndex=73|IndexInSheet=28|OwnerPartId=-1|Location.X=1448|Location.Y=820|Color=8388608|FontID=1|IsHidden=T|Text=5TS1|Name=Package
|RECORD=41|OwnerIndex=73|IndexInSheet=29|OwnerPartId=-1|Location.X=1448|Location.Y=820|Color=8388608|FontID=1|IsHidden=T|Text=EEPROM|Name=Device Class L3
|RECORD=41|OwnerIndex=73|IndexInSheet=30|OwnerPartId=-1|Location.X=1448|Location.Y=820|Color=8388608|FontID=1|IsHidden=T|Text=No|Name=Automotive
|RECORD=41|OwnerIndex=73|IndexInSheet=31|OwnerPartId=-1|Location.X=1448|Location.Y=820|Color=8388608|FontID=1|IsHidden=T|Text=0.55us|Name=Access Time
|RECORD=41|OwnerIndex=73|IndexInSheet=32|OwnerPartId=-1|Location.X=1448|Location.Y=820|Color=8388608|FontID=1|IsHidden=T|Text=Memory|Name=Device Class L2
|RECORD=41|OwnerIndex=73|IndexInSheet=33|OwnerPartId=-1|Location.X=1448|Location.Y=820|Color=8388608|FontID=1|IsHidden=T|Text=Yes|Name=Lead Free
|RECORD=41|OwnerIndex=73|IndexInSheet=34|OwnerPartId=-1|Location.X=1448|Location.Y=820|Color=8388608|FontID=1|IsHidden=T|Text=I2C,2-Wire|Name=Interface
|RECORD=34|OwnerIndex=73|IndexInSheet=-1|OwnerPartId=-1|Location.X=1470|Location.Y=820|Color=8388608|FontID=1|Text=U7|Name=Designator|ReadOnlyState=1
|RECORD=41|OwnerIndex=73|IndexInSheet=-1|OwnerPartId=1|Location.X=1470|Location.Y=750|Color=8388608|FontID=1|Text=AT24MAC402-STUM-T|Name=Comment
|RECORD=44|OwnerIndex=73
|RECORD=45|OwnerIndex=116|IndexInSheet=-1|UseComponentLibrary=T|ModelName=FP-5TS1-IPC_C|ModelType=PCBLIB|DatafileCount=1|ModelDatafileEntity0=FP-5TS1-IPC_C|ModelDatafileKind0=PCBLib|IsCurrent=T|DatalinksLocked=T|DatabaseDatalinksLocked=T
|RECORD=46|OwnerIndex=117
|RECORD=48|OwnerIndex=117
|RECORD=45|OwnerIndex=116|IndexInSheet=-1|UseComponentLibrary=T|ModelName=FP-5TS1-IPC_B|ModelType=PCBLIB|DatafileCount=1|ModelDatafileEntity0=FP-5TS1-IPC_B|ModelDatafileKind0=PCBLib|DatalinksLocked=T|DatabaseDatalinksLocked=T
|RECORD=46|OwnerIndex=120
|RECORD=48|OwnerIndex=120
|RECORD=45|OwnerIndex=116|IndexInSheet=-1|UseComponentLibrary=T|ModelName=FP-5TS1-IPC_A|ModelType=PCBLIB|DatafileCount=1|ModelDatafileEntity0=FP-5TS1-IPC_A|ModelDatafileKind0=PCBLib|DatalinksLocked=T|DatabaseDatalinksLocked=T
|RECORD=46|OwnerIndex=123
|RECORD=48|OwnerIndex=123
|RECORD=17|IndexInSheet=16|OwnerPartId=-1|ShowNetName=T|Location.X=1640|Location.Y=800|Color=255|FontID=1|Text=SDA|IsCrossSheetConnector=T
|RECORD=17|IndexInSheet=17|OwnerPartId=-1|ShowNetName=T|Location.X=1640|Location.Y=810|Color=255|FontID=1|Text=SCL|IsCrossSheetConnector=T
|RECORD=17|IndexInSheet=18|OwnerPartId=-1|ShowNetName=T|Location.X=1410|Location.Y=860|Orientation=1|Color=128|FontID=1|Text=+3.3V
|RECORD=17|IndexInSheet=19|OwnerPartId=-1|Style=4|ShowNetName=T|Location.X=1600|Location.Y=710|Orientation=3|Color=128|FontID=1|Text=GND
|RECORD=1|LibReference=CAP|ComponentDescription=C0603X104K5RACAUTO|PartCount=2|DisplayModeCount=2|IndexInSheet=20|OwnerPartId=-1|Location.X=230|Location.Y=820|Orientation=1|CurrentPartId=1|SourceLibraryName=Altium Content Vault|TargetFileName=*|AreaColor=11599871|Color=128|PartIDLocked=F|DesignItemId=CMP-2006-00003-1|AllPinCount=2
|RECORD=2|OwnerIndex=130|OwnerPartId=1|OwnerPartDisplayMode=1|FormalType=1|Electrical=4|PinConglomerate=35|PinLength=10|Location.X=240|Location.Y=820|Name=1|Designator=1|PinPropagationDelay=0.000000E+000
|RECORD=2|OwnerIndex=130|OwnerPartId=1|OwnerPartDisplayMode=1|FormalType=1|Electrical=4|PinConglomerate=33|PinLength=10|Location.X=240|Location.Y=830|Name=2|Designator=2|PinPropagationDelay=0.000000E+000
|RECORD=13|OwnerIndex=130|IsNotAccesible=T|IndexInSheet=2|OwnerPartId=1|OwnerPartDisplayMode=1|Location.X=248|Location.Y=820|Corner.X=232|Corner.Y=820|LineWidth=1|Color=16711680
|RECORD=13|OwnerIndex=130|IsNotAccesible=T|IndexInSheet=3|OwnerPartId=1|OwnerPartDisplayMode=1|Location.X=240|Location.Y=824|Corner.X=240|Corner.Y=830|LineWidth=1|Color=16711680
|RECORD=12|OwnerIndex=130|IsNotAccesible=T|IndexInSheet=4|OwnerPartId=1|OwnerPartDisplayMode=1|Location.X=240|Location.Y=840|Radius=16|LineWidth=1|StartAngle=241.000|EndAngle=270.000|Color=16711680
|RECORD=12|OwnerIndex=130|IsNotAccesible=T|IndexInSheet=5|OwnerPartId=1|OwnerPartDisplayMode=1|Location.X=240|Location.Y=840|Radius=16|LineWidth=1|StartAngle=270.000|EndAngle=299.000|Color=16711680
|RECORD=2|OwnerIndex=130|OwnerPartId=1|FormalType=1|Electrical=4|PinConglomerate=35|PinLength=10|Location.X=240|Location.Y=820|Name=1|Designator=1|PinPropagationDelay=0.000000E+000
|RECORD=2|OwnerIndex=130|OwnerPartId=1|FormalType=1|Electrical=4|PinConglomerate=33|PinLength=10|Location.X=240|Location.Y=830|Name=2|Designator=2|PinPropagationDelay=0.000000E+000
|RECORD=13|OwnerIndex=130|IsNotAccesible=T|IndexInSheet=8|OwnerPartId=1|Location.X=232|Location.Y=827|Corner.X=248|Corner.Y=827|LineWidth=1|Color=16711680
|RECORD=13|OwnerIndex=130|IsNotAccesible=T|IndexInSheet=9|OwnerPartId=1|Location.X=248|Location.Y=823|Corner.X=232|Corner.Y=823|LineWidth=1|Color=16711680
|RECORD=6|OwnerIndex=130|IsNotAccesible=T|IndexInSheet=10|OwnerPartId=1|LineWidth=1|Color=16711680|LocationCount=2|X1=240|Y1=820|X2=240|Y2=823
|RECORD=6|OwnerIndex=130|IsNotAccesible=T|IndexInSheet=11|OwnerPartId=1|LineWidth=1|Color=16711680|LocationCount=2|X1=240|Y1=830|X2=240|Y2=827
|RECORD=41|OwnerIndex=130|IndexInSheet=12|OwnerPartId=-1|Location.X=231|Location.Y=842|Color=8388608|FontID=1|IsHidden=T|Text=Kemet|Name=Manufacturer
|RECORD=41|OwnerIndex=130|IndexInSheet=13|OwnerPartId=-1|Location.X=231|Location.Y=842|Color=8388608|FontID=1|IsHidden=T|Text=C0603X104K5RACAUTO|Name=Part Number
|RECORD=34|OwnerIndex=130|IndexInSheet=-1|OwnerPartId=-1|Location.X=249|Location.Y=821|Color=8388608|FontID=1|Text=C59|Name=Designator|ReadOnlyState=1
|RECORD=41|OwnerIndex=130|IndexInSheet=-1|OwnerPartId=-1|Location.X=249|Location.Y=811|Color=8388608|FontID=1|Text=0.1uF|Name=Comment
|RECORD=44|OwnerIndex=130
|RECORD=45|OwnerIndex=151|IndexInSheet=-1|Description=Chip Capacitor, 2-Leads, Body 1.60x0.80mm, IPC Low Density|UseComponentLibrary=T|ModelName=CAPC1608X87X45ML20T05|ModelType=PCBLIB|DatafileCount=1|ModelDatafileEntity0=CAPC1608X87X45ML20T05|ModelDatafileKind0=PCBLib|IsCurrent=T|DatalinksLocked=T|DatabaseDatalinksLocked=T
|RECORD=46|OwnerIndex=152
|RECORD=48|OwnerIndex=152
|RECORD=41|OwnerIndex=154|IndexInSheet=-1|OwnerPartId=-1|Color=8388608|FontID=1|Text=2D|Name=Available Preview Images
|RECORD=45|OwnerIndex=151|IndexInSheet=-1|Description=Chip Capacitor, 2-Leads, Body 1.60x0.80mm, IPC High Density|UseComponentLibrary=T|ModelName=CAPC1608X87X45LL20T05|ModelType=PCBLIB|DatafileCount=1|ModelDatafileEntity0=CAPC1608X87X45LL20T05|ModelDatafileKind0=PCBLib|DatalinksLocked=T|DatabaseDatalinksLocked=T
|RECORD=46|OwnerIndex=156
|RECORD=48|OwnerIndex=156
|RECORD=41|OwnerIndex=158|IndexInSheet=-1|OwnerPartId=-1|Color=8388608|FontID=1|Text=2D|Name=Available Preview Images
|RECORD=45|OwnerIndex=151|IndexInSheet=-1|Description=Chip Capacitor, 2-Leads, Body 1.60x0.80mm, IPC Medium Density|UseComponentLibrary=T|ModelName=CAPC1608X87X45NL20T05|ModelType=PCBLIB|DatafileCount=1|ModelDatafileEntity0=CAPC1608X87X45NL20T05|ModelDatafileKind0=PCBLib|DatalinksLocked=T|DatabaseDatalinksLocked=T
|RECORD=46|OwnerIndex=160
|RECORD=48|OwnerIndex=160
|RECORD=41|OwnerIndex=162|IndexInSheet=-1|OwnerPartId=-1|Color=8388608|FontID=1|Text=2D|Name=Available Preview Images
|RECORD=1|LibReference=CAP|ComponentDescription=C0603X104K5RACAUTO|PartCount=2|DisplayModeCount=2|IndexInSheet=21|OwnerPartId=-1|Location.X=330|Location.Y=820|Orientation=1|CurrentPartId=1|SourceLibraryName=Altium Content Vault|TargetFileName=*|AreaColor=11599871|Color=128|PartIDLocked=F|DesignItemId=CMP-2006-00003-1|AllPinCount=2
|RECORD=2|OwnerIndex=164|OwnerPartId=1|OwnerPartDisplayMode=1|FormalType=1|Electrical=4|PinConglomerate=35|PinLength=10|Location.X=340|Location.Y=820|Name=1|Designator=1|PinPropagationDelay=0.000000E+000
|RECORD=2|OwnerIndex=164|OwnerPartId=1|OwnerPartDisplayMode=1|FormalType=1|Electrical=4|PinConglomerate=33|PinLength=10|Location.X=340|Location.Y=830|Name=2|Designator=2|PinPropagationDelay=0.000000E+000
|RECORD=13|OwnerIndex=164|IsNotAccesible=T|IndexInSheet=2|OwnerPartId=1|OwnerPartDisplayMode=1|Location.X=348|Location.Y=820|Corner.X=332|Corner.Y=820|LineWidth=1|Color=16711680
|RECORD=13|OwnerIndex=164|IsNotAccesible=T|IndexInSheet=3|OwnerPartId=1|OwnerPartDisplayMode=1|Location.X=340|Location.Y=824|Corner.X=340|Corner.Y=830|LineWidth=1|Color=16711680
|RECORD=12|OwnerIndex=164|IsNotAccesible=T|IndexInSheet=4|OwnerPartId=1|OwnerPartDisplayMode=1|Location.X=340|Location.Y=840|Radius=16|LineWidth=1|StartAngle=241.000|EndAngle=270.000|Color=16711680
|RECORD=12|OwnerIndex=164|IsNotAccesible=T|IndexInSheet=5|OwnerPartId=1|OwnerPartDisplayMode=1|Location.X=340|Location.Y=840|Radius=16|LineWidth=1|StartAngle=270.000|EndAngle=299.000|Color=16711680
|RECORD=2|OwnerIndex=164|OwnerPartId=1|FormalType=1|Electrical=4|PinConglomerate=35|PinLength=10|Location.X=340|Location.Y=820|Name=1|Designator=1|PinPropagationDelay=0.000000E+000
|RECORD=2|OwnerIndex=164|OwnerPartId=1|FormalType=1|Electrical=4|PinConglomerate=33|PinLength=10|Location.X=340|Location.Y=830|Name=2|Designator=2|PinPropagationDelay=0.000000E+000
|RECORD=13|OwnerIndex=164|IsNotAccesible=T|IndexInSheet=8|OwnerPartId=1|Location.X=332|Location.Y=827|Corner.X=348|Corner.Y=827|LineWidth=1|Color=16711680
|RECORD=13|OwnerIndex=164|IsNotAccesible=T|IndexInSheet=9|OwnerPartId=1|Location.X=348|Location.Y=823|Corner.X=332|Corner.Y=823|LineWidth=1|Color=16711680
|RECORD=6|OwnerIndex=164|IsNotAccesible=T|IndexInSheet=10|OwnerPartId=1|LineWidth=1|Color=16711680|LocationCount=2|X1=340|Y1=820|X2=340|Y2=823
|RECORD=6|OwnerIndex=164|IsNotAccesible=T|IndexInSheet=11|OwnerPartId=1|LineWidth=1|Color=16711680|LocationCount=2|X1=340|Y1=830|X2=340|Y2=827
|RECORD=41|OwnerIndex=164|IndexInSheet=12|OwnerPartId=-1|Location.X=331|Location.Y=842|Color=8388608|FontID=1|IsHidden=T|Text=Kemet|Name=Manufacturer
|RECORD=41|OwnerIndex=164|IndexInSheet=13|OwnerPartId=-1|Location.X=331|Location.Y=842|Color=8388608|FontID=1|IsHidden=T|Text=C0603X104K5RACAUTO|Name=Part Number
|RECORD=34|OwnerIndex=164|IndexInSheet=-1|OwnerPartId=-1|Location.X=349|Location.Y=821|Color=8388608|FontID=1|Text=C61|Name=Designator|ReadOnlyState=1
|RECORD=41|OwnerIndex=164|IndexInSheet=-1|OwnerPartId=-1|Location.X=349|Location.Y=811|Color=8388608|FontID=1|Text=0.1uF|Name=Comment
|RECORD=44|OwnerIndex=164
|RECORD=45|OwnerIndex=185|IndexInSheet=-1|Description=Chip Capacitor, 2-Leads, Body 1.60x0.80mm, IPC Low Density|UseComponentLibrary=T|ModelName=CAPC1608X87X45ML20T05|ModelType=PCBLIB|DatafileCount=1|ModelDatafileEntity0=CAPC1608X87X45ML20T05|ModelDatafileKind0=PCBLib|IsCurrent=T|DatalinksLocked=T|DatabaseDatalinksLocked=T
|RECORD=46|OwnerIndex=186
|RECORD=48|OwnerIndex=186
|RECORD=41|OwnerIndex=188|IndexInSheet=-1|OwnerPartId=-1|Color=8388608|FontID=1|Text=2D|Name=Available Preview Images
|RECORD=45|OwnerIndex=185|IndexInSheet=-1|Description=Chip Capacitor, 2-Leads, Body 1.60x0.80mm, IPC High Density|UseComponentLibrary=T|ModelName=CAPC1608X87X45LL20T05|ModelType=PCBLIB|DatafileCount=1|ModelDatafileEntity0=CAPC1608X87X45LL20T05|ModelDatafileKind0=PCBLib|DatalinksLocked=T|DatabaseDatalinksLocked=T
|RECORD=46|OwnerIndex=190
|RECORD=48|OwnerIndex=190
|RECORD=41|OwnerIndex=192|IndexInSheet=-1|OwnerPartId=-1|Color=8388608|FontID=1|Text=2D|Name=Available Preview Images
|RECORD=45|OwnerIndex=185|IndexInSheet=-1|Description=Chip Capacitor, 2-Leads, Body 1.60x0.80mm, IPC Medium Density|UseComponentLibrary=T|ModelName=CAPC1608X87X45NL20T05|ModelType=PCBLIB|DatafileCount=1|ModelDatafileEntity0=CAPC1608X87X45NL20T05|ModelDatafileKind0=PCBLib|DatalinksLocked=T|DatabaseDatalinksLocked=T
|RECORD=46|OwnerIndex=194
|RECORD=48|OwnerIndex=194
|RECORD=41|OwnerIndex=196|IndexInSheet=-1|OwnerPartId=-1|Color=8388608|FontID=1|Text=2D|Name=Available Preview Images
|RECORD=1|LibReference=CAP|ComponentDescription=C0603X104K5RACAUTO|PartCount=2|DisplayModeCount=2|IndexInSheet=22|OwnerPartId=-1|Location.X=1400|Location.Y=730|Orientation=1|CurrentPartId=1|SourceLibraryName=Altium Content Vault|TargetFileName=*|AreaColor=11599871|Color=128|PartIDLocked=F|DesignItemId=CMP-2006-00003-1|AllPinCount=2
|RECORD=2|OwnerIndex=198|OwnerPartId=1|OwnerPartDisplayMode=1|FormalType=1|Electrical=4|PinConglomerate=35|PinLength=10|Location.X=1410|Location.Y=730|Name=1|Designator=1|PinPropagationDelay=0.000000E+000
|RECORD=2|OwnerIndex=198|OwnerPartId=1|OwnerPartDisplayMode=1|FormalType=1|Electrical=4|PinConglomerate=33|PinLength=10|Location.X=1410|Location.Y=740|Name=2|Designator=2|PinPropagationDelay=0.000000E+000
|RECORD=13|OwnerIndex=198|IsNotAccesible=T|IndexInSheet=2|OwnerPartId=1|OwnerPartDisplayMode=1|Location.X=1418|Location.Y=730|Corner.X=1402|Corner.Y=730|LineWidth=1|Color=16711680
|RECORD=13|OwnerIndex=198|IsNotAccesible=T|IndexInSheet=3|OwnerPartId=1|OwnerPartDisplayMode=1|Location.X=1410|Location.Y=734|Corner.X=1410|Corner.Y=740|LineWidth=1|Color=16711680
|RECORD=12|OwnerIndex=198|IsNotAccesible=T|IndexInSheet=4|OwnerPartId=1|OwnerPartDisplayMode=1|Location.X=1410|Location.Y=750|Radius=16|LineWidth=1|StartAngle=241.000|EndAngle=270.000|Color=16711680
|RECORD=12|OwnerIndex=198|IsNotAccesible=T|IndexInSheet=5|OwnerPartId=1|OwnerPartDisplayMode=1|Location.X=1410|Location.Y=750|Radius=16|LineWidth=1|StartAngle=270.000|EndAngle=299.000|Color=16711680
|RECORD=2|OwnerIndex=198|OwnerPartId=1|FormalType=1|Electrical=4|PinConglomerate=35|PinLength=10|Location.X=1410|Location.Y=730|Name=1|Designator=1|PinPropagationDelay=0.000000E+000
|RECORD=2|OwnerIndex=198|OwnerPartId=1|FormalType=1|Electrical=4|PinConglomerate=33|PinLength=10|Location.X=1410|Location.Y=740|Name=2|Designator=2|PinPropagationDelay=0.000000E+000
|RECORD=13|OwnerIndex=198|IsNotAccesible=T|IndexInSheet=8|OwnerPartId=1|Location.X=1402|Location.Y=737|Corner.X=1418|Corner.Y=737|LineWidth=1|Color=16711680
|RECORD=13|OwnerIndex=198|IsNotAccesible=T|IndexInSheet=9|OwnerPartId=1|Location.X=1418|Location.Y=733|Corner.X=1402|Corner.Y=733|LineWidth=1|Color=16711680
|RECORD=6|OwnerIndex=198|IsNotAccesible=T|IndexInSheet=10|OwnerPartId=1|LineWidth=1|Color=16711680|LocationCount=2|X1=1410|Y1=730|X2=1410|Y2=733
|RECORD=6|OwnerIndex=198|IsNotAccesible=T|IndexInSheet=11|OwnerPartId=1|LineWidth=1|Color=16711680|LocationCount=2|X1=1410|Y1=740|X2=1410|Y2=737
|RECORD=41|OwnerIndex=198|IndexInSheet=12|OwnerPartId=-1|Location.X=1401|Location.Y=752|Color=8388608|FontID=1|IsHidden=T|Text=Kemet|Name=Manufacturer
|RECORD=41|OwnerIndex=198|IndexInSheet=13|OwnerPartId=-1|Location.X=1401|Location.Y=752|Color=8388608|FontID=1|IsHidden=T|Text=C0603X104K5RACAUTO|Name=Part Number
|RECORD=34|OwnerIndex=198|IndexInSheet=-1|OwnerPartId=-1|Location.X=1419|Location.Y=731|Color=8388608|FontID=1|Text=C25|Name=Designator|ReadOnlyState=1
|RECORD=41|OwnerIndex=198|IndexInSheet=-1|OwnerPartId=-1|Location.X=1419|Location.Y=721|Color=8388608|FontID=1|Text=0.1uF|Name=Comment
|RECORD=44|OwnerIndex=198
|RECORD=45|OwnerIndex=219|IndexInSheet=-1|Description=Chip Capacitor, 2-Leads, Body 1.60x0.80mm, IPC Low Density|UseComponentLibrary=T|ModelName=CAPC1608X87X45ML20T05|ModelType=PCBLIB|DatafileCount=1|ModelDatafileEntity0=CAPC1608X87X45ML20T05|ModelDatafileKind0=PCBLib|IsCurrent=T|DatalinksLocked=T|DatabaseDatalinksLocked=T
|RECORD=46|OwnerIndex=220
|RECORD=48|OwnerIndex=220
|RECORD=41|OwnerIndex=222|IndexInSheet=-1|OwnerPartId=-1|Color=8388608|FontID=1|Text=2D|Name=Available Preview Images
|RECORD=45|OwnerIndex=219|IndexInSheet=-1|Description=Chip Capacitor, 2-Leads, Body 1.60x0.80mm, IPC High Density|UseComponentLibrary=T|ModelName=CAPC1608X87X45LL20T05|ModelType=PCBLIB|DatafileCount=1|ModelDatafileEntity0=CAPC1608X87X45LL20T05|ModelDatafileKind0=PCBLib|DatalinksLocked=T|DatabaseDatalinksLocked=T
|RECORD=46|OwnerIndex=224
|RECORD=48|OwnerIndex=224
|RECORD=41|OwnerIndex=226|IndexInSheet=-1|OwnerPartId=-1|Color=8388608|FontID=1|Text=2D|Name=Available Preview Images
|RECORD=45|OwnerIndex=219|IndexInSheet=-1|Description=Chip Capacitor, 2-Leads, Body 1.60x0.80mm, IPC Medium Density|UseComponentLibrary=T|ModelName=CAPC1608X87X45NL20T05|ModelType=PCBLIB|DatafileCount=1|ModelDatafileEntity0=CAPC1608X87X45NL20T05|ModelDatafileKind0=PCBLib|DatalinksLocked=T|DatabaseDatalinksLocked=T
|RECORD=46|OwnerIndex=228
|RECORD=48|OwnerIndex=228
|RECORD=41|OwnerIndex=230|IndexInSheet=-1|OwnerPartId=-1|Color=8388608|FontID=1|Text=2D|Name=Available Preview Images
|RECORD=17|IndexInSheet=23|OwnerPartId=-1|ShowNetName=T|Location.X=1360|Location.Y=860|Orientation=1|Color=128|FontID=1|Text=+3.3V
|RECORD=17|IndexInSheet=24|OwnerPartId=-1|Style=4|ShowNetName=T|Location.X=1410|Location.Y=710|Orientation=3|Color=128|FontID=1|Text=GND
|RECORD=17|IndexInSheet=25|OwnerPartId=-1|ShowNetName=T|Location.X=1340|Location.Y=770|Orientation=2|Color=255|FontID=1|Text=EXT_EEPROM_WP|IsCrossSheetConnector=T
|RECORD=1|LibReference=RES-2|ComponentDescription=Chip Resistor, 10 KOhm, +/- 1%, 0.1 W, -55 to 155 degC, 0603 (1608 Metric), RoHS, Tape and Reel RMCF0603FT10K0|PartCount=2|DisplayModeCount=1|IndexInSheet=26|OwnerPartId=-1|Location.X=1360|Location.Y=810|Orientation=1|CurrentPartId=1|LibraryPath=*|SourceLibraryName=Altium Content Vault|TargetFileName=*|AreaColor=11599871|Color=128|PartIDLocked=T|DesignItemId=CMP-2000-06990-1|AllPinCount=2
|RECORD=2|OwnerIndex=235|OwnerPartId=1|FormalType=1|Electrical=4|PinConglomerate=33|PinLength=10|Location.X=1360|Location.Y=830|Name=2|Designator=2|PinPropagationDelay=0.000000E+000
|RECORD=2|OwnerIndex=235|OwnerPartId=1|FormalType=1|Electrical=4|PinConglomerate=35|PinLength=10|Location.X=1360|Location.Y=810|Name=1|Designator=1|PinPropagationDelay=0.000000E+000
|RECORD=6|OwnerIndex=235|IsNotAccesible=T|IndexInSheet=2|OwnerPartId=1|LineWidth=1|Color=16711680|LocationCount=10|X1=1360|Y1=830|X2=1360|Y2=826|X3=1362|Y3=825|X4=1358|Y4=823|X5=1362|Y5=821|X6=1358|Y6=819|X7=1362|Y7=817|X8=1358|Y8=815|X9=1360|Y9=814|X10=1360|Y10=810
|RECORD=41|OwnerIndex=235|IndexInSheet=3|OwnerPartId=-1|Location.X=1357|Location.Y=842|Color=8388608|FontID=1|IsHidden=T|Text=0603(1608Metric)|Name=Package / Case
|RECORD=41|OwnerIndex=235|IndexInSheet=4|OwnerPartId=-1|Location.X=1357|Location.Y=842|Color=8388608|FontID=1|IsHidden=T|Text=01/2017|Name=Datasheet Version
|RECORD=41|OwnerIndex=235|IndexInSheet=5|OwnerPartId=-1|Location.X=1357|Location.Y=842|Color=8388608|FontID=1|IsHidden=T|Text=10k|Name=Resistance (Ohms)
|RECORD=41|OwnerIndex=235|IndexInSheet=6|OwnerPartId=-1|Location.X=1357|Location.Y=842|Color=8388608|FontID=1|IsHidden=T|Text=AutomotiveAEC-Q200|Name=Features
|RECORD=41|OwnerIndex=235|IndexInSheet=7|OwnerPartId=-1|Location.X=1357|Location.Y=842|Color=8388608|FontID=1|IsHidden=T|Text=CutTape(CT)|Name=Packaging
|RECORD=41|OwnerIndex=235|IndexInSheet=8|OwnerPartId=-1|Location.X=1357|Location.Y=842|Color=8388608|FontID=1|IsHidden=T|Text=RMCF|Name=Series
|RECORD=41|OwnerIndex=235|IndexInSheet=9|OwnerPartId=-1|Location.X=1357|Location.Y=842|Color=8388608|FontID=1|IsHidden=T|Text=0.022"(0.55mm)|Name=Height
|RECORD=41|OwnerIndex=235|IndexInSheet=10|OwnerPartId=-1|Location.X=1357|Location.Y=842|Color=8388608|FontID=1|IsHidden=T|Text=±1%|Name=Tolerance
|RECORD=41|OwnerIndex=235|IndexInSheet=11|OwnerPartId=-1|Location.X=1357|Location.Y=842|Color=8388608|FontID=3|IsHidden=T|Text=https://www.seielect.com/|Name=Manufacturer URL
|RECORD=41|OwnerIndex=235|IndexInSheet=12|OwnerPartId=-1|Location.X=1357|Location.Y=842|Color=8388608|FontID=3|IsHidden=T|Text=https://www.seielect.com/Catalog/SEI-RMCF_RMCP.pdf|Name=Datasheet URL
|RECORD=41|OwnerIndex=235|IndexInSheet=13|OwnerPartId=-1|Location.X=1357|Location.Y=842|Color=8388608|FontID=1|IsHidden=T|Text=0603|Name=Supplier Device Package
|RECORD=41|OwnerIndex=235|IndexInSheet=14|OwnerPartId=-1|Location.X=1357|Location.Y=842|Color=8388608|FontID=1|IsHidden=T|Text=2|Name=Number of Terminations
|RECORD=41|OwnerIndex=235|IndexInSheet=15|OwnerPartId=-1|Location.X=1357|Location.Y=842|Color=8388608|FontID=1|IsHidden=T|Text=ChipResistor-SurfaceMount|Name=Family
|RECORD=41|OwnerIndex=235|IndexInSheet=16|OwnerPartId=-1|Location.X=1357|Location.Y=842|Color=8388608|FontID=1|IsHidden=T|Text=0603|Name=Package Reference
|RECORD=41|OwnerIndex=235|IndexInSheet=17|OwnerPartId=-1|Location.X=1357|Location.Y=842|Color=8388608|FontID=1|IsHidden=T|Text=0.061"Lx0.031"W(1.55mmx0.80mm)|Name=Size / Dimension
|RECORD=41|OwnerIndex=235|IndexInSheet=18|OwnerPartId=-1|Location.X=1357|Location.Y=842|Color=8388608|FontID=1|IsHidden=T|Text=SurfaceMount|Name=Mounting Technology
|RECORD=41|OwnerIndex=235|IndexInSheet=19|OwnerPartId=-1|Location.X=1357|Location.Y=842|Color=8388608|FontID=1|IsHidden=T|Text=2-Pin Surface Mount Device, Body 1.55 x 0.8 mm|Name=Package Description
|RECORD=41|OwnerIndex=235|IndexInSheet=20|OwnerPartId=-1|Location.X=1357|Location.Y=842|Color=8388608|FontID=1|IsHidden=T|Text=-55°C~155°C|Name=Operating Temperature
|RECORD=41|OwnerIndex=235|IndexInSheet=21|OwnerPartId=-1|Location.X=1357|Location.Y=842|Color=8388608|FontID=1|IsHidden=T|Text=±100ppm/°C|Name=Temperature Coefficient
|RECORD=41|OwnerIndex=235|IndexInSheet=22|OwnerPartId=-1|Location.X=1357|Location.Y=842|Color=8388608|FontID=1|IsHidden=T|Text=ThickFilm|Name=Composition
|RECORD=41|OwnerIndex=235|IndexInSheet=23|OwnerPartId=-1|Location.X=1357|Location.Y=842|Color=8388608|FontID=1|IsHidden=T|Text=0.1W,1/10W|Name=Power (Watts)
|RECORD=41|OwnerIndex=235|IndexInSheet=24|OwnerPartId=-1|Location.X=1357|Location.Y=842|Color=8388608|FontID=1|IsHidden=T|Text=Stackpole-Electronics-Inc.|Name=Manufacturer
|RECORD=41|OwnerIndex=235|IndexInSheet=25|OwnerPartId=-1|Location.X=1357|Location.Y=842|Color=8388608|FontID=1|IsHidden=T|Text=Resistors|Name=Category
|RECORD=34|OwnerIndex=235|IndexInSheet=-1|OwnerPartId=-1|Location.X=1363|Location.Y=821|Color=8388608|FontID=1|Text=R37|Name=Designator|ReadOnlyState=1
|RECORD=41|OwnerIndex=235|IndexInSheet=-1|OwnerPartId=-1|Location.X=1363|Location.Y=811|Color=8388608|FontID=1|Text=10K|Name=Comment
|RECORD=44|OwnerIndex=235
|RECORD=45|OwnerIndex=266|IndexInSheet=-1|Description=Chip Resistor, 2-Leads, Body 1.7x0.95mm, IPC High Density|UseComponentLibrary=T|ModelName=RESC1608X55X30LL15T20|ModelType=PCBLIB|DatafileCount=1|ModelDatafileEntity0=RESC1608X55X30LL15T20|ModelDatafileKind0=PCBLib|IsCurrent=T|DatalinksLocked=T|DatabaseDatalinksLocked=T
|RECORD=46|OwnerIndex=267
|RECORD=48|OwnerIndex=267
|RECORD=41|OwnerIndex=269|IndexInSheet=-1|OwnerPartId=-1|Color=8388608|FontID=1|Text=2D|Name=Available Preview Images
|RECORD=45|OwnerIndex=266|IndexInSheet=-1|Description=Chip Resistor, 2-Leads, Body 1.7x0.95mm, IPC Low Density|UseComponentLibrary=T|ModelName=RESC1608X55X30ML15T20|ModelType=PCBLIB|DatafileCount=1|ModelDatafileEntity0=RESC1608X55X30ML15T20|ModelDatafileKind0=PCBLib|DatalinksLocked=T|DatabaseDatalinksLocked=T
|RECORD=46|OwnerIndex=271
|RECORD=48|OwnerIndex=271
|RECORD=41|OwnerIndex=273|IndexInSheet=-1|OwnerPartId=-1|Color=8388608|FontID=1|Text=2D|Name=Available Preview Images
|RECORD=45|OwnerIndex=266|IndexInSheet=-1|Description=Chip Resistor, 2-Leads, Body 1.7x0.95mm, IPC Medium Density|UseComponentLibrary=T|ModelName=RESC1608X55X30NL15T20|ModelType=PCBLIB|DatafileCount=1|ModelDatafileEntity0=RESC1608X55X30NL15T20|ModelDatafileKind0=PCBLib|DatalinksLocked=T|DatabaseDatalinksLocked=T
|RECORD=46|OwnerIndex=275
|RECORD=48|OwnerIndex=275
|RECORD=41|OwnerIndex=277|IndexInSheet=-1|OwnerPartId=-1|Color=8388608|FontID=1|Text=2D|Name=Available Preview Images
|RECORD=41|IndexInSheet=27|OwnerPartId=-1|Color=8388608|FontID=1|IsHidden=T|Name=ConfigurationParameters|ReadOnlyState=1
|RECORD=41|IndexInSheet=28|OwnerPartId=-1|Color=8388608|FontID=1|IsHidden=T|Name=ConfiguratorName|ReadOnlyState=1
|RECORD=41|IndexInSheet=29|OwnerPartId=-1|Color=8388608|FontID=1|IsHidden=T|Name=VersionControl_RevNumber|ReadOnlyState=1
|RECORD=41|IndexInSheet=30|OwnerPartId=-1|Color=8388608|FontID=1|IsHidden=T|Name=IsUserConfigurable|ReadOnlyState=1
|RECORD=41|IndexInSheet=31|OwnerPartId=-1|Color=8388608|FontID=1|IsHidden=T|Name=VersionControl_ProjFolderRevNumber|ReadOnlyState=1
|RECORD=41|IndexInSheet=32|OwnerPartId=-1|Color=8388608|FontID=1|IsHidden=T|Text=|Name=SPICEModelCache|ReadOnlyState=1
|RECORD=4|IndexInSheet=33|OwnerPartId=-1|Location.X=1460|Location.Y=856|Color=8388608|FontID=8|Text=EEPROM
|RECORD=1|LibReference=d58e2f6669bc67e6a2bc6a28610ca79|ComponentDescription=SENSOR PRESSURE HUMIDITY TEMP|PartCount=2|DisplayModeCount=1|IndexInSheet=34|OwnerPartId=-1|Location.X=710|Location.Y=320|CurrentPartId=1|LibraryPath=*|SourceLibraryName=Altium Content Vault|TargetFileName=*|AreaColor=11599871|Color=128|PartIDLocked=T|DesignItemId=CMP-2000-05073-3|AllPinCount=8
|RECORD=14|OwnerIndex=286|IsNotAccesible=T|OwnerPartId=1|Location.X=730|Location.Y=250|Corner.X=830|Corner.Y=330|LineWidth=1|Color=128|AreaColor=11599871|IsSolid=T
|RECORD=2|OwnerIndex=286|OwnerPartId=1|Electrical=7|PinConglomerate=58|PinLength=20|Location.X=730|Location.Y=320|Name=VDD|Designator=8|PinPropagationDelay=0.000000E+000
|RECORD=2|OwnerIndex=286|OwnerPartId=1|Electrical=7|PinConglomerate=58|PinLength=20|Location.X=730|Location.Y=310|Name=VDDIO|Designator=6|PinPropagationDelay=0.000000E+000
|RECORD=2|OwnerIndex=286|OwnerPartId=1|PinConglomerate=56|PinLength=20|Location.X=830|Location.Y=290|Name=C\S\|Designator=2|PinPropagationDelay=0.000000E+000
|RECORD=2|OwnerIndex=286|OwnerPartId=1|SymBol_InnerEdge=3|PinConglomerate=56|PinLength=20|Location.X=830|Location.Y=320|Name=SCK|Designator=4|PinPropagationDelay=0.000000E+000
|RECORD=2|OwnerIndex=286|OwnerPartId=1|Electrical=1|PinConglomerate=56|PinLength=20|Location.X=830|Location.Y=310|Name=SDI|Designator=3|PinPropagationDelay=0.000000E+000
|RECORD=2|OwnerIndex=286|OwnerPartId=1|Electrical=1|PinConglomerate=56|PinLength=20|Location.X=830|Location.Y=300|Name=SDO|Designator=5|PinPropagationDelay=0.000000E+000
|RECORD=2|OwnerIndex=286|OwnerPartId=1|Electrical=7|PinConglomerate=56|PinLength=20|Location.X=830|Location.Y=270|Name=GND|Designator=1|PinPropagationDelay=0.000000E+000
|RECORD=2|OwnerIndex=286|OwnerPartId=1|Electrical=7|PinConglomerate=56|PinLength=20|Location.X=830|Location.Y=260|Name=GND|Designator=7|PinPropagationDelay=0.000000E+000
|RECORD=41|OwnerIndex=286|IndexInSheet=9|OwnerPartId=-1|Location.X=708|Location.Y=330|Color=8388608|FontID=1|IsHidden=T|Text=Temperature|Name=Sensor Type
|RECORD=41|OwnerIndex=286|IndexInSheet=10|OwnerPartId=-1|Location.X=708|Location.Y=330|Color=8388608|FontID=1|IsHidden=T|Text=-40°C|Name=Min Operating Temperature
|RECORD=41|OwnerIndex=286|IndexInSheet=11|OwnerPartId=-1|Location.X=708|Location.Y=330|Color=8388608|FontID=1|IsHidden=T|Text=3%|Name=Accuracy
|RECORD=41|OwnerIndex=286|IndexInSheet=12|OwnerPartId=-1|Location.X=708|Location.Y=330|Color=8388608|FontID=1|IsHidden=T|Text=85°C|Name=Max Operating Temperature
|RECORD=41|OwnerIndex=286|IndexInSheet=13|OwnerPartId=-1|Location.X=708|Location.Y=330|Color=8388608|FontID=1|IsHidden=T|Text=LGA|Name=Case/Package
|RECORD=41|OwnerIndex=286|IndexInSheet=14|OwnerPartId=-1|Location.X=708|Location.Y=330|Color=8388608|FontID=1|IsHidden=T|Text=Cut Tape|Name=Packaging
|RECORD=41|OwnerIndex=286|IndexInSheet=15|OwnerPartId=-1|Location.X=708|Location.Y=330|Color=8388608|FontID=1|IsHidden=T|Text=Surface Mount|Name=Mount
|RECORD=41|OwnerIndex=286|IndexInSheet=16|OwnerPartId=-1|Location.X=708|Location.Y=330|Color=8388608|FontID=1|IsHidden=T|Text=1s|Name=Response Time
|RECORD=41|OwnerIndex=286|IndexInSheet=17|OwnerPartId=-1|Location.X=708|Location.Y=330|Color=8388608|FontID=1|IsHidden=T|Text=SPI|Name=Output Type
|RECORD=41|OwnerIndex=286|IndexInSheet=18|OwnerPartId=-1|Location.X=708|Location.Y=330|Color=8388608|FontID=1|IsHidden=T|Text=Lead Free|Name=Lead Free
|RECORD=41|OwnerIndex=286|IndexInSheet=19|OwnerPartId=-1|Location.X=708|Location.Y=330|Color=8388608|FontID=1|IsHidden=T|Text=8|Name=Number of Pins
|RECORD=34|OwnerIndex=286|IndexInSheet=-1|OwnerPartId=-1|Location.X=730|Location.Y=330|Color=8388608|FontID=1|Text=U14|Name=Designator|ReadOnlyState=1
|RECORD=41|OwnerIndex=286|IndexInSheet=-1|OwnerPartId=1|Location.X=730|Location.Y=240|Color=8388608|FontID=1|Text=BME280|Name=Comment
|RECORD=44|OwnerIndex=286
|RECORD=45|OwnerIndex=317|IndexInSheet=-1|UseComponentLibrary=T|ModelName=FP-BME280-MFG|ModelType=PCBLIB|DatafileCount=1|ModelDatafileEntity0=FP-BME280-MFG|ModelDatafileKind0=PCBLib|IsCurrent=T|DatalinksLocked=T|DatabaseDatalinksLocked=T
|RECORD=46|OwnerIndex=318
|RECORD=48|OwnerIndex=318
|RECORD=17|IndexInSheet=35|OwnerPartId=-1|Style=4|ShowNetName=T|Location.X=680|Location.Y=170|Orientation=3|Color=128|FontID=1|Text=GND
|RECORD=17|IndexInSheet=36|OwnerPartId=-1|Style=4|ShowNetName=T|Location.X=630|Location.Y=170|Orientation=3|Color=128|FontID=1|Text=GND
|RECORD=1|LibReference=CAP|ComponentDescription=C0603X104K5RACAUTO|PartCount=2|DisplayModeCount=2|IndexInSheet=37|OwnerPartId=-1|Location.X=670|Location.Y=200|Orientation=1|CurrentPartId=1|SourceLibraryName=Altium Content Vault|TargetFileName=*|AreaColor=11599871|Color=128|PartIDLocked=F|DesignItemId=CMP-2006-00003-1|AllPinCount=2
|RECORD=2|OwnerIndex=323|OwnerPartId=1|OwnerPartDisplayMode=1|FormalType=1|Electrical=4|PinConglomerate=35|PinLength=10|Location.X=680|Location.Y=200|Name=1|Designator=1|PinPropagationDelay=0.000000E+000
|RECORD=2|OwnerIndex=323|OwnerPartId=1|OwnerPartDisplayMode=1|FormalType=1|Electrical=4|PinConglomerate=33|PinLength=10|Location.X=680|Location.Y=210|Name=2|Designator=2|PinPropagationDelay=0.000000E+000
|RECORD=13|OwnerIndex=323|IsNotAccesible=T|IndexInSheet=2|OwnerPartId=1|OwnerPartDisplayMode=1|Location.X=688|Location.Y=200|Corner.X=672|Corner.Y=200|LineWidth=1|Color=16711680
|RECORD=13|OwnerIndex=323|IsNotAccesible=T|IndexInSheet=3|OwnerPartId=1|OwnerPartDisplayMode=1|Location.X=680|Location.Y=204|Corner.X=680|Corner.Y=210|LineWidth=1|Color=16711680
|RECORD=12|OwnerIndex=323|IsNotAccesible=T|IndexInSheet=4|OwnerPartId=1|OwnerPartDisplayMode=1|Location.X=680|Location.Y=220|Radius=16|LineWidth=1|StartAngle=241.000|EndAngle=270.000|Color=16711680
|RECORD=12|OwnerIndex=323|IsNotAccesible=T|IndexInSheet=5|OwnerPartId=1|OwnerPartDisplayMode=1|Location.X=680|Location.Y=220|Radius=16|LineWidth=1|StartAngle=270.000|EndAngle=299.000|Color=16711680
|RECORD=2|OwnerIndex=323|OwnerPartId=1|FormalType=1|Electrical=4|PinConglomerate=35|PinLength=10|Location.X=680|Location.Y=200|Name=1|Designator=1|PinPropagationDelay=0.000000E+000
|RECORD=2|OwnerIndex=323|OwnerPartId=1|FormalType=1|Electrical=4|PinConglomerate=33|PinLength=10|Location.X=680|Location.Y=210|Name=2|Designator=2|PinPropagationDelay=0.000000E+000
|RECORD=13|OwnerIndex=323|IsNotAccesible=T|IndexInSheet=8|OwnerPartId=1|Location.X=672|Location.Y=207|Corner.X=688|Corner.Y=207|LineWidth=1|Color=16711680
|RECORD=13|OwnerIndex=323|IsNotAccesible=T|IndexInSheet=9|OwnerPartId=1|Location.X=688|Location.Y=203|Corner.X=672|Corner.Y=203|LineWidth=1|Color=16711680
|RECORD=6|OwnerIndex=323|IsNotAccesible=T|IndexInSheet=10|OwnerPartId=1|LineWidth=1|Color=16711680|LocationCount=2|X1=680|Y1=200|X2=680|Y2=203
|RECORD=6|OwnerIndex=323|IsNotAccesible=T|IndexInSheet=11|OwnerPartId=1|LineWidth=1|Color=16711680|LocationCount=2|X1=680|Y1=210|X2=680|Y2=207
|RECORD=41|OwnerIndex=323|IndexInSheet=12|OwnerPartId=-1|Location.X=671|Location.Y=222|Color=8388608|FontID=1|IsHidden=T|Text=Kemet|Name=Manufacturer
|RECORD=41|OwnerIndex=323|IndexInSheet=13|OwnerPartId=-1|Location.X=671|Location.Y=222|Color=8388608|FontID=1|IsHidden=T|Text=C0603X104K5RACAUTO|Name=Part Number
|RECORD=34|OwnerIndex=323|IndexInSheet=-1|OwnerPartId=-1|Location.X=689|Location.Y=201|Color=8388608|FontID=1|Text=C31|Name=Designator|ReadOnlyState=1
|RECORD=41|OwnerIndex=323|IndexInSheet=-1|OwnerPartId=-1|Location.X=689|Location.Y=191|Color=8388608|FontID=1|Text=0.1uF|Name=Comment
|RECORD=44|OwnerIndex=323
|RECORD=45|OwnerIndex=344|IndexInSheet=-1|Description=Chip Capacitor, 2-Leads, Body 1.60x0.80mm, IPC Low Density|UseComponentLibrary=T|ModelName=CAPC1608X87X45ML20T05|ModelType=PCBLIB|DatafileCount=1|ModelDatafileEntity0=CAPC1608X87X45ML20T05|ModelDatafileKind0=PCBLib|IsCurrent=T|DatalinksLocked=T|DatabaseDatalinksLocked=T
|RECORD=46|OwnerIndex=345
|RECORD=48|OwnerIndex=345
|RECORD=41|OwnerIndex=347|IndexInSheet=-1|OwnerPartId=-1|Color=8388608|FontID=1|Text=2D|Name=Available Preview Images
|RECORD=45|OwnerIndex=344|IndexInSheet=-1|Description=Chip Capacitor, 2-Leads, Body 1.60x0.80mm, IPC High Density|UseComponentLibrary=T|ModelName=CAPC1608X87X45LL20T05|ModelType=PCBLIB|DatafileCount=1|ModelDatafileEntity0=CAPC1608X87X45LL20T05|ModelDatafileKind0=PCBLib|DatalinksLocked=T|DatabaseDatalinksLocked=T
|RECORD=46|OwnerIndex=349
|RECORD=48|OwnerIndex=349
|RECORD=41|OwnerIndex=351|IndexInSheet=-1|OwnerPartId=-1|Color=8388608|FontID=1|Text=2D|Name=Available Preview Images
|RECORD=45|OwnerIndex=344|IndexInSheet=-1|Description=Chip Capacitor, 2-Leads, Body 1.60x0.80mm, IPC Medium Density|UseComponentLibrary=T|ModelName=CAPC1608X87X45NL20T05|ModelType=PCBLIB|DatafileCount=1|ModelDatafileEntity0=CAPC1608X87X45NL20T05|ModelDatafileKind0=PCBLib|DatalinksLocked=T|DatabaseDatalinksLocked=T
|RECORD=46|OwnerIndex=353
|RECORD=48|OwnerIndex=353
|RECORD=41|OwnerIndex=355|IndexInSheet=-1|OwnerPartId=-1|Color=8388608|FontID=1|Text=2D|Name=Available Preview Images
|RECORD=1|LibReference=CAP|ComponentDescription=C0603X104K5RACAUTO|PartCount=2|DisplayModeCount=2|IndexInSheet=38|OwnerPartId=-1|Location.X=620|Location.Y=200|Orientation=1|CurrentPartId=1|SourceLibraryName=Altium Content Vault|TargetFileName=*|AreaColor=11599871|Color=128|PartIDLocked=F|DesignItemId=CMP-2006-00003-1|AllPinCount=2
|RECORD=2|OwnerIndex=357|OwnerPartId=1|OwnerPartDisplayMode=1|FormalType=1|Electrical=4|PinConglomerate=35|PinLength=10|Location.X=630|Location.Y=200|Name=1|Designator=1|PinPropagationDelay=0.000000E+000
|RECORD=2|OwnerIndex=357|OwnerPartId=1|OwnerPartDisplayMode=1|FormalType=1|Electrical=4|PinConglomerate=33|PinLength=10|Location.X=630|Location.Y=210|Name=2|Designator=2|PinPropagationDelay=0.000000E+000
|RECORD=13|OwnerIndex=357|IsNotAccesible=T|IndexInSheet=2|OwnerPartId=1|OwnerPartDisplayMode=1|Location.X=638|Location.Y=200|Corner.X=622|Corner.Y=200|LineWidth=1|Color=16711680
|RECORD=13|OwnerIndex=357|IsNotAccesible=T|IndexInSheet=3|OwnerPartId=1|OwnerPartDisplayMode=1|Location.X=630|Location.Y=204|Corner.X=630|Corner.Y=210|LineWidth=1|Color=16711680
|RECORD=12|OwnerIndex=357|IsNotAccesible=T|IndexInSheet=4|OwnerPartId=1|OwnerPartDisplayMode=1|Location.X=630|Location.Y=220|Radius=16|LineWidth=1|StartAngle=241.000|EndAngle=270.000|Color=16711680
|RECORD=12|OwnerIndex=357|IsNotAccesible=T|IndexInSheet=5|OwnerPartId=1|OwnerPartDisplayMode=1|Location.X=630|Location.Y=220|Radius=16|LineWidth=1|StartAngle=270.000|EndAngle=299.000|Color=16711680
|RECORD=2|OwnerIndex=357|OwnerPartId=1|FormalType=1|Electrical=4|PinConglomerate=35|PinLength=10|Location.X=630|Location.Y=200|Name=1|Designator=1|PinPropagationDelay=0.000000E+000
|RECORD=2|OwnerIndex=357|OwnerPartId=1|FormalType=1|Electrical=4|PinConglomerate=33|PinLength=10|Location.X=630|Location.Y=210|Name=2|Designator=2|PinPropagationDelay=0.000000E+000
|RECORD=13|OwnerIndex=357|IsNotAccesible=T|IndexInSheet=8|OwnerPartId=1|Location.X=622|Location.Y=207|Corner.X=638|Corner.Y=207|LineWidth=1|Color=16711680
|RECORD=13|OwnerIndex=357|IsNotAccesible=T|IndexInSheet=9|OwnerPartId=1|Location.X=638|Location.Y=203|Corner.X=622|Corner.Y=203|LineWidth=1|Color=16711680
|RECORD=6|OwnerIndex=357|IsNotAccesible=T|IndexInSheet=10|OwnerPartId=1|LineWidth=1|Color=16711680|LocationCount=2|X1=630|Y1=200|X2=630|Y2=203
|RECORD=6|OwnerIndex=357|IsNotAccesible=T|IndexInSheet=11|OwnerPartId=1|LineWidth=1|Color=16711680|LocationCount=2|X1=630|Y1=210|X2=630|Y2=207
|RECORD=41|OwnerIndex=357|IndexInSheet=12|OwnerPartId=-1|Location.X=621|Location.Y=222|Color=8388608|FontID=1|IsHidden=T|Text=Kemet|Name=Manufacturer
|RECORD=41|OwnerIndex=357|IndexInSheet=13|OwnerPartId=-1|Location.X=621|Location.Y=222|Color=8388608|FontID=1|IsHidden=T|Text=C0603X104K5RACAUTO|Name=Part Number
|RECORD=34|OwnerIndex=357|IndexInSheet=-1|OwnerPartId=-1|Location.X=639|Location.Y=201|Color=8388608|FontID=1|Text=C30|Name=Designator|ReadOnlyState=1
|RECORD=41|OwnerIndex=357|IndexInSheet=-1|OwnerPartId=-1|Location.X=639|Location.Y=191|Color=8388608|FontID=1|Text=0.1uF|Name=Comment
|RECORD=44|OwnerIndex=357
|RECORD=45|OwnerIndex=378|IndexInSheet=-1|Description=Chip Capacitor, 2-Leads, Body 1.60x0.80mm, IPC Low Density|UseComponentLibrary=T|ModelName=CAPC1608X87X45ML20T05|ModelType=PCBLIB|DatafileCount=1|ModelDatafileEntity0=CAPC1608X87X45ML20T05|ModelDatafileKind0=PCBLib|IsCurrent=T|DatalinksLocked=T|DatabaseDatalinksLocked=T
|RECORD=46|OwnerIndex=379
|RECORD=48|OwnerIndex=379
|RECORD=41|OwnerIndex=381|IndexInSheet=-1|OwnerPartId=-1|Color=8388608|FontID=1|Text=2D|Name=Available Preview Images
|RECORD=45|OwnerIndex=378|IndexInSheet=-1|Description=Chip Capacitor, 2-Leads, Body 1.60x0.80mm, IPC High Density|UseComponentLibrary=T|ModelName=CAPC1608X87X45LL20T05|ModelType=PCBLIB|DatafileCount=1|ModelDatafileEntity0=CAPC1608X87X45LL20T05|ModelDatafileKind0=PCBLib|DatalinksLocked=T|DatabaseDatalinksLocked=T
|RECORD=46|OwnerIndex=383
|RECORD=48|OwnerIndex=383
|RECORD=41|OwnerIndex=385|IndexInSheet=-1|OwnerPartId=-1|Color=8388608|FontID=1|Text=2D|Name=Available Preview Images
|RECORD=45|OwnerIndex=378|IndexInSheet=-1|Description=Chip Capacitor, 2-Leads, Body 1.60x0.80mm, IPC Medium Density|UseComponentLibrary=T|ModelName=CAPC1608X87X45NL20T05|ModelType=PCBLIB|DatafileCount=1|ModelDatafileEntity0=CAPC1608X87X45NL20T05|ModelDatafileKind0=PCBLib|DatalinksLocked=T|DatabaseDatalinksLocked=T
|RECORD=46|OwnerIndex=387
|RECORD=48|OwnerIndex=387
|RECORD=41|OwnerIndex=389|IndexInSheet=-1|OwnerPartId=-1|Color=8388608|FontID=1|Text=2D|Name=Available Preview Images
|RECORD=17|IndexInSheet=39|OwnerPartId=-1|ShowNetName=T|Location.X=680|Location.Y=370|Orientation=1|Color=128|FontID=1|Text=+3.3V
|RECORD=17|IndexInSheet=40|OwnerPartId=-1|ShowNetName=T|Location.X=630|Location.Y=370|Orientation=1|Color=128|FontID=1|Text=+3.3V
|RECORD=17|IndexInSheet=41|OwnerPartId=-1|ShowNetName=T|Location.X=930|Location.Y=320|Color=255|FontID=1|Text=SENS_I2C_SCL|IsCrossSheetConnector=T
|RECORD=17|IndexInSheet=42|OwnerPartId=-1|ShowNetName=T|Location.X=930|Location.Y=310|Color=255|FontID=1|Text=SENS_I2C_SDA|IsCrossSheetConnector=T
|RECORD=17|IndexInSheet=43|OwnerPartId=-1|ShowNetName=T|Location.X=890|Location.Y=370|Orientation=1|Color=128|FontID=1|Text=+3.3V
|RECORD=17|IndexInSheet=44|OwnerPartId=-1|Style=4|ShowNetName=T|Location.X=890|Location.Y=170|Orientation=3|Color=128|FontID=1|Text=GND
|RECORD=17|IndexInSheet=45|OwnerPartId=-1|Style=4|ShowNetName=T|Location.X=930|Location.Y=170|Orientation=3|Color=128|FontID=1|Text=GND
|RECORD=4|IndexInSheet=46|OwnerPartId=-1|Location.X=670|Location.Y=410|Color=8388608|FontID=8|Text=ENVIRONMENT (0x76)
|RECORD=4|IndexInSheet=47|OwnerPartId=-1|Location.X=1160|Location.Y=100|Color=8388608|FontID=8|Text=IMU (0x29) , BNO080 alternative allowed
|RECORD=17|IndexInSheet=48|OwnerPartId=-1|Style=4|ShowNetName=T|Location.X=600|Location.Y=580|Orientation=3|Color=128|FontID=1|Text=GND
|RECORD=17|IndexInSheet=49|OwnerPartId=-1|Style=4|ShowNetName=T|Location.X=80|Location.Y=590|Orientation=3|Color=128|FontID=1|Text=GND
|RECORD=17|IndexInSheet=50|OwnerPartId=-1|Style=4|ShowNetName=T|Location.X=180|Location.Y=590|Orientation=3|Color=128|FontID=1|Text=GND
|RECORD=17|IndexInSheet=51|OwnerPartId=-1|ShowNetName=T|Location.X=670|Location.Y=640|Color=255|FontID=1|Text=RCB_GPS2_TP2|IsCrossSheetConnector=T
|RECORD=17|IndexInSheet=52|OwnerPartId=-1|ShowNetName=T|Location.X=670|Location.Y=630|Color=255|FontID=1|Text=RCB_GPS2_TP1|IsCrossSheetConnector=T
|RECORD=17|IndexInSheet=53|OwnerPartId=-1|ShowNetName=T|Location.X=670|Location.Y=620|Color=255|FontID=1|Text=RCB_GPS2_RX|IsCrossSheetConnector=T
|RECORD=17|IndexInSheet=54|OwnerPartId=-1|ShowNetName=T|Location.X=330|Location.Y=630|Orientation=2|Color=255|FontID=1|Text=RCB_GPS2_TX|IsCrossSheetConnector=T
|RECORD=17|IndexInSheet=55|OwnerPartId=-1|ShowNetName=T|Location.X=330|Location.Y=620|Orientation=2|Color=255|FontID=1|Text=GPS2_RST|IsCrossSheetConnector=T
|RECORD=1|LibReference=RCB-F9T|ComponentDescription=MOD, GPS|PartCount=2|DisplayModeCount=1|IndexInSheet=56|OwnerPartId=-1|Location.X=500|Location.Y=640|CurrentPartId=1|LibraryPath=*|SourceLibraryName=Modules.IntLib|TargetFileName=*|AreaColor=11599871|Color=128|PartIDLocked=F|PinsMoveable=T|DesignItemId=RCB-F9T|AllPinCount=8
|RECORD=41|OwnerIndex=408|OwnerPartId=-1|Location.X=500|Location.Y=640|Color=8388608|FontID=9|IsHidden=T|Text=RCB-F9T-1|Name=MFG PART NUM
|RECORD=41|OwnerIndex=408|IndexInSheet=1|OwnerPartId=-1|Location.X=500|Location.Y=640|Color=8388608|FontID=9|IsHidden=T|Text=UBLOCKS|Name=MFG NAME
|RECORD=41|OwnerIndex=408|IndexInSheet=2|OwnerPartId=-1|Location.X=500|Location.Y=640|Color=8388608|FontID=9|IsHidden=T|Text=MOD|Name=CATEGORY
|RECORD=41|OwnerIndex=408|IndexInSheet=3|OwnerPartId=-1|Location.X=500|Location.Y=640|Color=8388608|FontID=9|IsHidden=T|Text=9/11/13|Name=MODIFY DATE
|RECORD=41|OwnerIndex=408|IndexInSheet=4|OwnerPartId=-1|Location.X=498|Location.Y=389|Color=8388608|FontID=1|IsHidden=T|Text=GPS|Name=P1
|RECORD=41|OwnerIndex=408|IndexInSheet=5|OwnerPartId=-1|Location.X=498|Location.Y=389|Color=8388608|FontID=1|IsHidden=T|Name=P2
|RECORD=41|OwnerIndex=408|IndexInSheet=6|OwnerPartId=-1|Location.X=498|Location.Y=389|Color=8388608|FontID=1|IsHidden=T|Name=P3
|RECORD=41|OwnerIndex=408|IndexInSheet=7|OwnerPartId=-1|Location.X=498|Location.Y=389|Color=8388608|FontID=1|IsHidden=T|Name=OTHER
|RECORD=41|OwnerIndex=408|IndexInSheet=8|OwnerPartId=-1|Location.X=498|Location.Y=389|Color=8388608|FontID=1|IsHidden=T|Name=DATE
|RECORD=41|OwnerIndex=408|IndexInSheet=9|OwnerPartId=-1|Location.X=498|Location.Y=389|Color=8388608|FontID=1|IsHidden=T|Text=*|Name=SHEETPART
|RECORD=41|OwnerIndex=408|IndexInSheet=10|OwnerPartId=-1|Location.X=498|Location.Y=389|Color=8388608|FontID=1|IsHidden=T|Name=SUB
|RECORD=41|OwnerIndex=408|IndexInSheet=11|OwnerPartId=-1|Location.X=498|Location.Y=389|Color=8388608|FontID=1|IsHidden=T|Name=SIZE
|RECORD=41|OwnerIndex=408|IndexInSheet=12|OwnerPartId=-1|Location.X=498|Location.Y=389|Color=8388608|FontID=1|IsHidden=T|Text=-40C|Name=MINTEMP
|RECORD=41|OwnerIndex=408|IndexInSheet=13|OwnerPartId=-1|Location.X=498|Location.Y=389|Color=8388608|FontID=1|IsHidden=T|Text=80C|Name=MAXTEMP
|RECORD=41|OwnerIndex=408|IndexInSheet=14|OwnerPartId=-1|Location.X=498|Location.Y=379|Color=8388608|FontID=1|IsHidden=T|Text=.|Name=DATE
|RECORD=41|OwnerIndex=408|IndexInSheet=15|OwnerPartId=-1|Location.X=498|Location.Y=694|Color=8388608|FontID=1|IsHidden=T|Text=MOD BLE 4.2|Name=DESC
|RECORD=41|OwnerIndex=408|IndexInSheet=16|OwnerPartId=-1|Location.X=468|Location.Y=712|Color=8388608|FontID=1|IsHidden=T|Text=<V PART NUM>|Name=VELENTIUM PART NUM
|RECORD=41|OwnerIndex=408|IndexInSheet=17|OwnerPartId=-1|Location.X=418|Location.Y=694|Color=8388608|FontID=1|IsHidden=T|Text=Digi-Key|Name=Supplier 1|ReadOnlyState=3
|RECORD=41|OwnerIndex=408|IndexInSheet=18|OwnerPartId=-1|Location.X=418|Location.Y=694|Color=8388608|FontID=1|IsHidden=T|Text=672-RCB-F9T-ND|Name=Supplier Part Number 1|ReadOnlyState=3
|RECORD=14|OwnerIndex=408|IsNotAccesible=T|IndexInSheet=19|OwnerPartId=1|Location.X=450|Location.Y=610|Corner.X=550|Corner.Y=660|Color=128|AreaColor=11599871|IsSolid=T
|RECORD=2|OwnerIndex=408|OwnerPartId=1|FormalType=1|Electrical=4|PinConglomerate=26|PinLength=30|Location.X=450|Location.Y=650|Name=VCC_ANT|Designator=1|SwapIDPart=Ž&Ž||PinPropagationDelay=0.000000E+000
|RECORD=2|OwnerIndex=408|OwnerPartId=1|FormalType=1|Electrical=4|PinConglomerate=26|PinLength=30|Location.X=450|Location.Y=640|Name=VCC|Designator=2|SwapIDPart=Ž&Ž||PinPropagationDelay=0.000000E+000
|RECORD=2|OwnerIndex=408|OwnerPartId=1|FormalType=1|Electrical=4|PinConglomerate=26|PinLength=30|Location.X=450|Location.Y=630|Name=TXD|Designator=3|SwapIDPart=Ž&Ž||PinPropagationDelay=0.000000E+000
|RECORD=2|OwnerIndex=408|OwnerPartId=1|FormalType=1|Electrical=4|PinConglomerate=26|PinLength=30|Location.X=450|Location.Y=620|Name=RST|Designator=4|SwapIDPart=Ž&Ž||PinPropagationDelay=0.000000E+000
|RECORD=2|OwnerIndex=408|OwnerPartId=1|FormalType=1|Electrical=4|PinConglomerate=24|PinLength=30|Location.X=550|Location.Y=620|Name=RXD|Designator=5|SwapIDPart=Ž&Ž||PinPropagationDelay=0.000000E+000
|RECORD=2|OwnerIndex=408|OwnerPartId=1|FormalType=1|Electrical=4|PinConglomerate=24|PinLength=30|Location.X=550|Location.Y=630|Name=TP1|Designator=6|SwapIDPart=Ž&Ž||PinPropagationDelay=0.000000E+000
|RECORD=2|OwnerIndex=408|OwnerPartId=1|FormalType=1|Electrical=4|PinConglomerate=24|PinLength=30|Location.X=550|Location.Y=640|Name=TP2|Designator=7|SwapIDPart=Ž&Ž||PinPropagationDelay=0.000000E+000
|RECORD=2|OwnerIndex=408|OwnerPartId=1|FormalType=1|Electrical=4|PinConglomerate=24|PinLength=30|Location.X=550|Location.Y=650|Name=GND|Designator=8|SwapIDPart=Ž&Ž||PinPropagationDelay=0.000000E+000
|RECORD=34|OwnerIndex=408|IndexInSheet=-1|OwnerPartId=-1|Location.X=450|Location.Y=660|Color=8388608|FontID=1|Text=U15|Name=Designator|ReadOnlyState=1
|RECORD=41|OwnerIndex=408|IndexInSheet=-1|OwnerPartId=-1|Location.X=450|Location.Y=598|Color=8388608|FontID=1|Text=RCB-F9T-1|Name=Comment
|RECORD=44|OwnerIndex=408
|RECORD=45|OwnerIndex=447|IndexInSheet=-1|ModelName=GNSS|ModelType=PCBLIB|DatafileCount=1|ModelDatafileEntity0=GNSS|ModelDatafileKind0=PCBLib|IsCurrent=T|IntegratedModel=T|DatabaseModel=T
|RECORD=46|OwnerIndex=448
|RECORD=48|OwnerIndex=448
|RECORD=1|LibReference=CAP|ComponentDescription=C0603X104K5RACAUTO|PartCount=2|DisplayModeCount=2|IndexInSheet=57|OwnerPartId=-1|Location.X=120|Location.Y=610|Orientation=1|CurrentPartId=1|SourceLibraryName=Altium Content Vault|TargetFileName=*|AreaColor=11599871|Color=128|PartIDLocked=F|DesignItemId=CMP-2006-00003-1|AllPinCount=2
|RECORD=2|OwnerIndex=451|OwnerPartId=1|OwnerPartDisplayMode=1|FormalType=1|Electrical=4|PinConglomerate=35|PinLength=10|Location.X=130|Location.Y=610|Name=1|Designator=1|PinPropagationDelay=0.000000E+000
|RECORD=2|OwnerIndex=451|OwnerPartId=1|OwnerPartDisplayMode=1|FormalType=1|Electrical=4|PinConglomerate=33|PinLength=10|Location.X=130|Location.Y=620|Name=2|Designator=2|PinPropagationDelay=0.000000E+000
|RECORD=13|OwnerIndex=451|IsNotAccesible=T|IndexInSheet=2|OwnerPartId=1|OwnerPartDisplayMode=1|Location.X=138|Location.Y=610|Corner.X=122|Corner.Y=610|LineWidth=1|Color=16711680
|RECORD=13|OwnerIndex=451|IsNotAccesible=T|IndexInSheet=3|OwnerPartId=1|OwnerPartDisplayMode=1|Location.X=130|Location.Y=614|Corner.X=130|Corner.Y=620|LineWidth=1|Color=16711680
|RECORD=12|OwnerIndex=451|IsNotAccesible=T|IndexInSheet=4|OwnerPartId=1|OwnerPartDisplayMode=1|Location.X=130|Location.Y=630|Radius=16|LineWidth=1|StartAngle=241.000|EndAngle=270.000|Color=16711680
|RECORD=12|OwnerIndex=451|IsNotAccesible=T|IndexInSheet=5|OwnerPartId=1|OwnerPartDisplayMode=1|Location.X=130|Location.Y=630|Radius=16|LineWidth=1|StartAngle=270.000|EndAngle=299.000|Color=16711680
|RECORD=2|OwnerIndex=451|OwnerPartId=1|FormalType=1|Electrical=4|PinConglomerate=35|PinLength=10|Location.X=130|Location.Y=610|Name=1|Designator=1|PinPropagationDelay=0.000000E+000
|RECORD=2|OwnerIndex=451|OwnerPartId=1|FormalType=1|Electrical=4|PinConglomerate=33|PinLength=10|Location.X=130|Location.Y=620|Name=2|Designator=2|PinPropagationDelay=0.000000E+000
|RECORD=13|OwnerIndex=451|IsNotAccesible=T|IndexInSheet=8|OwnerPartId=1|Location.X=122|Location.Y=617|Corner.X=138|Corner.Y=617|LineWidth=1|Color=16711680
|RECORD=13|OwnerIndex=451|IsNotAccesible=T|IndexInSheet=9|OwnerPartId=1|Location.X=138|Location.Y=613|Corner.X=122|Corner.Y=613|LineWidth=1|Color=16711680
|RECORD=6|OwnerIndex=451|IsNotAccesible=T|IndexInSheet=10|OwnerPartId=1|LineWidth=1|Color=16711680|LocationCount=2|X1=130|Y1=610|X2=130|Y2=613
|RECORD=6|OwnerIndex=451|IsNotAccesible=T|IndexInSheet=11|OwnerPartId=1|LineWidth=1|Color=16711680|LocationCount=2|X1=130|Y1=620|X2=130|Y2=617
|RECORD=41|OwnerIndex=451|IndexInSheet=12|OwnerPartId=-1|Location.X=121|Location.Y=632|Color=8388608|FontID=1|IsHidden=T|Text=Kemet|Name=Manufacturer
|RECORD=41|OwnerIndex=451|IndexInSheet=13|OwnerPartId=-1|Location.X=121|Location.Y=632|Color=8388608|FontID=1|IsHidden=T|Text=C0603X104K5RACAUTO|Name=Part Number
|RECORD=34|OwnerIndex=451|IndexInSheet=-1|OwnerPartId=-1|Location.X=139|Location.Y=611|Color=8388608|FontID=1|Text=C36|Name=Designator|ReadOnlyState=1
|RECORD=41|OwnerIndex=451|IndexInSheet=-1|OwnerPartId=-1|Location.X=139|Location.Y=601|Color=8388608|FontID=1|Text=0.1uF|Name=Comment
|RECORD=44|OwnerIndex=451
|RECORD=45|OwnerIndex=472|IndexInSheet=-1|Description=Chip Capacitor, 2-Leads, Body 1.60x0.80mm, IPC Low Density|UseComponentLibrary=T|ModelName=CAPC1608X87X45ML20T05|ModelType=PCBLIB|DatafileCount=1|ModelDatafileEntity0=CAPC1608X87X45ML20T05|ModelDatafileKind0=PCBLib|IsCurrent=T|DatalinksLocked=T|DatabaseDatalinksLocked=T
|RECORD=46|OwnerIndex=473
|RECORD=48|OwnerIndex=473
|RECORD=41|OwnerIndex=475|IndexInSheet=-1|OwnerPartId=-1|Color=8388608|FontID=1|Text=2D|Name=Available Preview Images
|RECORD=45|OwnerIndex=472|IndexInSheet=-1|Description=Chip Capacitor, 2-Leads, Body 1.60x0.80mm, IPC High Density|UseComponentLibrary=T|ModelName=CAPC1608X87X45LL20T05|ModelType=PCBLIB|DatafileCount=1|ModelDatafileEntity0=CAPC1608X87X45LL20T05|ModelDatafileKind0=PCBLib|DatalinksLocked=T|DatabaseDatalinksLocked=T
|RECORD=46|OwnerIndex=477
|RECORD=48|OwnerIndex=477
|RECORD=41|OwnerIndex=479|IndexInSheet=-1|OwnerPartId=-1|Color=8388608|FontID=1|Text=2D|Name=Available Preview Images
|RECORD=45|OwnerIndex=472|IndexInSheet=-1|Description=Chip Capacitor, 2-Leads, Body 1.60x0.80mm, IPC Medium Density|UseComponentLibrary=T|ModelName=CAPC1608X87X45NL20T05|ModelType=PCBLIB|DatafileCount=1|ModelDatafileEntity0=CAPC1608X87X45NL20T05|ModelDatafileKind0=PCBLib|DatalinksLocked=T|DatabaseDatalinksLocked=T
|RECORD=46|OwnerIndex=481
|RECORD=48|OwnerIndex=481
|RECORD=41|OwnerIndex=483|IndexInSheet=-1|OwnerPartId=-1|Color=8388608|FontID=1|Text=2D|Name=Available Preview Images
|RECORD=1|LibReference=CAP|ComponentDescription=C0603X104K5RACAUTO|PartCount=2|DisplayModeCount=2|IndexInSheet=58|OwnerPartId=-1|Location.X=220|Location.Y=610|Orientation=1|CurrentPartId=1|SourceLibraryName=Altium Content Vault|TargetFileName=*|AreaColor=11599871|Color=128|PartIDLocked=F|DesignItemId=CMP-2006-00003-1|AllPinCount=2
|RECORD=2|OwnerIndex=485|OwnerPartId=1|OwnerPartDisplayMode=1|FormalType=1|Electrical=4|PinConglomerate=35|PinLength=10|Location.X=230|Location.Y=610|Name=1|Designator=1|PinPropagationDelay=0.000000E+000
|RECORD=2|OwnerIndex=485|OwnerPartId=1|OwnerPartDisplayMode=1|FormalType=1|Electrical=4|PinConglomerate=33|PinLength=10|Location.X=230|Location.Y=620|Name=2|Designator=2|PinPropagationDelay=0.000000E+000
|RECORD=13|OwnerIndex=485|IsNotAccesible=T|IndexInSheet=2|OwnerPartId=1|OwnerPartDisplayMode=1|Location.X=238|Location.Y=610|Corner.X=222|Corner.Y=610|LineWidth=1|Color=16711680
|RECORD=13|OwnerIndex=485|IsNotAccesible=T|IndexInSheet=3|OwnerPartId=1|OwnerPartDisplayMode=1|Location.X=230|Location.Y=614|Corner.X=230|Corner.Y=620|LineWidth=1|Color=16711680
|RECORD=12|OwnerIndex=485|IsNotAccesible=T|IndexInSheet=4|OwnerPartId=1|OwnerPartDisplayMode=1|Location.X=230|Location.Y=630|Radius=16|LineWidth=1|StartAngle=241.000|EndAngle=270.000|Color=16711680
|RECORD=12|OwnerIndex=485|IsNotAccesible=T|IndexInSheet=5|OwnerPartId=1|OwnerPartDisplayMode=1|Location.X=230|Location.Y=630|Radius=16|LineWidth=1|StartAngle=270.000|EndAngle=299.000|Color=16711680
|RECORD=2|OwnerIndex=485|OwnerPartId=1|FormalType=1|Electrical=4|PinConglomerate=35|PinLength=10|Location.X=230|Location.Y=610|Name=1|Designator=1|PinPropagationDelay=0.000000E+000
|RECORD=2|OwnerIndex=485|OwnerPartId=1|FormalType=1|Electrical=4|PinConglomerate=33|PinLength=10|Location.X=230|Location.Y=620|Name=2|Designator=2|PinPropagationDelay=0.000000E+000
|RECORD=13|OwnerIndex=485|IsNotAccesible=T|IndexInSheet=8|OwnerPartId=1|Location.X=222|Location.Y=617|Corner.X=238|Corner.Y=617|LineWidth=1|Color=16711680
|RECORD=13|OwnerIndex=485|IsNotAccesible=T|IndexInSheet=9|OwnerPartId=1|Location.X=238|Location.Y=613|Corner.X=222|Corner.Y=613|LineWidth=1|Color=16711680
|RECORD=6|OwnerIndex=485|IsNotAccesible=T|IndexInSheet=10|OwnerPartId=1|LineWidth=1|Color=16711680|LocationCount=2|X1=230|Y1=610|X2=230|Y2=613
|RECORD=6|OwnerIndex=485|IsNotAccesible=T|IndexInSheet=11|OwnerPartId=1|LineWidth=1|Color=16711680|LocationCount=2|X1=230|Y1=620|X2=230|Y2=617
|RECORD=41|OwnerIndex=485|IndexInSheet=12|OwnerPartId=-1|Location.X=221|Location.Y=632|Color=8388608|FontID=1|IsHidden=T|Text=Kemet|Name=Manufacturer
|RECORD=41|OwnerIndex=485|IndexInSheet=13|OwnerPartId=-1|Location.X=221|Location.Y=632|Color=8388608|FontID=1|IsHidden=T|Text=C0603X104K5RACAUTO|Name=Part Number
|RECORD=34|OwnerIndex=485|IndexInSheet=-1|OwnerPartId=-1|Location.X=239|Location.Y=611|Color=8388608|FontID=1|Text=C37|Name=Designator|ReadOnlyState=1
|RECORD=41|OwnerIndex=485|IndexInSheet=-1|OwnerPartId=-1|Location.X=239|Location.Y=601|Color=8388608|FontID=1|Text=0.1uF|Name=Comment
|RECORD=44|OwnerIndex=485
|RECORD=45|OwnerIndex=506|IndexInSheet=-1|Description=Chip Capacitor, 2-Leads, Body 1.60x0.80mm, IPC Low Density|UseComponentLibrary=T|ModelName=CAPC1608X87X45ML20T05|ModelType=PCBLIB|DatafileCount=1|ModelDatafileEntity0=CAPC1608X87X45ML20T05|ModelDatafileKind0=PCBLib|IsCurrent=T|DatalinksLocked=T|DatabaseDatalinksLocked=T
|RECORD=46|OwnerIndex=507
|RECORD=48|OwnerIndex=507
|RECORD=41|OwnerIndex=509|IndexInSheet=-1|OwnerPartId=-1|Color=8388608|FontID=1|Text=2D|Name=Available Preview Images
|RECORD=45|OwnerIndex=506|IndexInSheet=-1|Description=Chip Capacitor, 2-Leads, Body 1.60x0.80mm, IPC High Density|UseComponentLibrary=T|ModelName=CAPC1608X87X45LL20T05|ModelType=PCBLIB|DatafileCount=1|ModelDatafileEntity0=CAPC1608X87X45LL20T05|ModelDatafileKind0=PCBLib|DatalinksLocked=T|DatabaseDatalinksLocked=T
|RECORD=46|OwnerIndex=511
|RECORD=48|OwnerIndex=511
|RECORD=41|OwnerIndex=513|IndexInSheet=-1|OwnerPartId=-1|Color=8388608|FontID=1|Text=2D|Name=Available Preview Images
|RECORD=45|OwnerIndex=506|IndexInSheet=-1|Description=Chip Capacitor, 2-Leads, Body 1.60x0.80mm, IPC Medium Density|UseComponentLibrary=T|ModelName=CAPC1608X87X45NL20T05|ModelType=PCBLIB|DatafileCount=1|ModelDatafileEntity0=CAPC1608X87X45NL20T05|ModelDatafileKind0=PCBLib|DatalinksLocked=T|DatabaseDatalinksLocked=T
|RECORD=46|OwnerIndex=515
|RECORD=48|OwnerIndex=515
|RECORD=41|OwnerIndex=517|IndexInSheet=-1|OwnerPartId=-1|Color=8388608|FontID=1|Text=2D|Name=Available Preview Images
|RECORD=1|LibReference=b4654b650e69147ec39a6b967a45e02|ComponentDescription=None|PartCount=2|DisplayModeCount=1|IndexInSheet=59|OwnerPartId=-1|Location.X=190|Location.Y=840|CurrentPartId=1|LibraryPath=*|SourceLibraryName=Altium Content Vault|TargetFileName=*|AreaColor=11599871|Color=128|PartIDLocked=T|DesignItemId=CMP-14477-000079-2|AllPinCount=2
|RECORD=2|OwnerIndex=519|OwnerPartId=1|Electrical=4|PinConglomerate=49|PinLength=7|Location.X=190|Location.Y=833|Name=1|Designator=1|PinPropagationDelay=0.000000E+000
|RECORD=2|OwnerIndex=519|OwnerPartId=1|Electrical=4|PinConglomerate=51|PinLength=6|Location.X=190|Location.Y=826|Name=2|Designator=2|PinPropagationDelay=0.000000E+000
|RECORD=13|OwnerIndex=519|IsNotAccesible=T|IndexInSheet=2|OwnerPartId=1|Location.X=200|Location.Y=833|Corner.X=180|Corner.Y=833|LineWidth=1|Color=16711680
|RECORD=13|OwnerIndex=519|IsNotAccesible=T|IndexInSheet=3|OwnerPartId=1|Location.X=200|Location.Y=827|Corner.X=180|Corner.Y=827|LineWidth=1|Color=16711680
|RECORD=13|OwnerIndex=519|IsNotAccesible=T|IndexInSheet=4|OwnerPartId=1|Location.X=190|Location.Y=833|Corner.X=190|Corner.Y=836|LineWidth=1|Color=16711680
|RECORD=13|OwnerIndex=519|IsNotAccesible=T|IndexInSheet=5|OwnerPartId=1|Location.X=190|Location.Y=826|Corner.X=190|Corner.Y=825|LineWidth=1|Color=16711680
|RECORD=41|OwnerIndex=519|IndexInSheet=6|OwnerPartId=-1|Location.X=179|Location.Y=842|Color=8388608|FontID=1|IsHidden=T|Text=Tape and Reel|Name=Packaging
|RECORD=41|OwnerIndex=519|IndexInSheet=7|OwnerPartId=-1|Location.X=179|Location.Y=842|Color=8388608|FontID=1|IsHidden=T|Text=10uF|Name=Capacitance
|RECORD=41|OwnerIndex=519|IndexInSheet=8|OwnerPartId=-1|Location.X=179|Location.Y=842|Color=8388608|FontID=1|IsHidden=T|Text=25V|Name=Voltage Rating (DC)
|RECORD=41|OwnerIndex=519|IndexInSheet=9|OwnerPartId=-1|Location.X=179|Location.Y=842|Color=8388608|FontID=1|IsHidden=T|Text=0.053inch|Name=Thickness
|RECORD=41|OwnerIndex=519|IndexInSheet=10|OwnerPartId=-1|Location.X=179|Location.Y=842|Color=8388608|FontID=1|IsHidden=T|Text=Ceramic|Name=Resistor Type
|RECORD=41|OwnerIndex=519|IndexInSheet=11|OwnerPartId=-1|Location.X=179|Location.Y=842|Color=8388608|FontID=1|IsHidden=T|Text=Yes|Name=RoHS Compliant
|RECORD=41|OwnerIndex=519|IndexInSheet=12|OwnerPartId=-1|Location.X=179|Location.Y=842|Color=8388608|FontID=1|IsHidden=T|Text=Lead Free|Name=Lead Free
|RECORD=41|OwnerIndex=519|IndexInSheet=13|OwnerPartId=-1|Location.X=179|Location.Y=842|Color=8388608|FontID=1|IsHidden=T|Text=No SVHC|Name=REACH SVHC
|RECORD=41|OwnerIndex=519|IndexInSheet=14|OwnerPartId=-1|Location.X=179|Location.Y=842|Color=8388608|FontID=1|IsHidden=T|Text=2|Name=Number of Pins
|RECORD=41|OwnerIndex=519|IndexInSheet=15|OwnerPartId=-1|Location.X=179|Location.Y=842|Color=8388608|FontID=1|IsHidden=T|Text=1|Name=Package Quantity
|RECORD=41|OwnerIndex=519|IndexInSheet=16|OwnerPartId=-1|Location.X=179|Location.Y=842|Color=8388608|FontID=1|IsHidden=T|Text=Surface Mount|Name=Mount
|RECORD=41|OwnerIndex=519|IndexInSheet=17|OwnerPartId=-1|Location.X=179|Location.Y=842|Color=8388608|FontID=1|IsHidden=T|Text=SMD/SMT|Name=Termination
|RECORD=41|OwnerIndex=519|IndexInSheet=18|OwnerPartId=-1|Location.X=179|Location.Y=842|Color=8388608|FontID=1|IsHidden=T|Text=0.049inch|Name=Width
|RECORD=41|OwnerIndex=519|IndexInSheet=19|OwnerPartId=-1|Location.X=179|Location.Y=842|Color=8388608|FontID=1|IsHidden=T|Text=85°C|Name=Max Operating Temperature
|RECORD=41|OwnerIndex=519|IndexInSheet=20|OwnerPartId=-1|Location.X=179|Location.Y=842|Color=8388608|FontID=1|IsHidden=T|Text=0.079inch|Name=Length
|RECORD=41|OwnerIndex=519|IndexInSheet=21|OwnerPartId=-1|Location.X=179|Location.Y=842|Color=8388608|FontID=1|IsHidden=T|Text=0805|Name=Case/Package
|RECORD=41|OwnerIndex=519|IndexInSheet=22|OwnerPartId=-1|Location.X=179|Location.Y=842|Color=8388608|FontID=1|IsHidden=T|Text=25V|Name=Voltage Rating
|RECORD=41|OwnerIndex=519|IndexInSheet=23|OwnerPartId=-1|Location.X=179|Location.Y=842|Color=8388608|FontID=1|IsHidden=T|Text=-55°C|Name=Min Operating Temperature
|RECORD=41|OwnerIndex=519|IndexInSheet=24|OwnerPartId=-1|Location.X=179|Location.Y=842|Color=8388608|FontID=1|IsHidden=T|Text=10%|Name=Tolerance
|RECORD=41|OwnerIndex=519|IndexInSheet=25|OwnerPartId=-1|Location.X=179|Location.Y=842|Color=8388608|FontID=1|IsHidden=T|Text=X7R|Name=Dielectric
|RECORD=41|OwnerIndex=519|IndexInSheet=26|OwnerPartId=-1|Location.X=179|Location.Y=842|Color=8388608|FontID=1|IsHidden=T|Text=2012|Name=Case Code (Metric)
|RECORD=41|OwnerIndex=519|IndexInSheet=27|OwnerPartId=-1|Location.X=179|Location.Y=842|Color=8388608|FontID=1|IsHidden=T|Text=0805|Name=Case Code (Imperial)
|RECORD=41|OwnerIndex=519|IndexInSheet=28|OwnerPartId=-1|Location.X=179|Location.Y=842|Color=8388608|FontID=1|IsHidden=T|Text=1.25mm|Name=Height
|RECORD=41|OwnerIndex=519|IndexInSheet=29|OwnerPartId=-1|Location.X=179|Location.Y=842|Color=8388608|FontID=1|IsHidden=T|Text=16V|Name=Voltage
|RECORD=41|OwnerIndex=519|IndexInSheet=30|OwnerPartId=-1|Location.X=179|Location.Y=842|Color=8388608|FontID=1|IsHidden=T|Text=M|Name=Series
|RECORD=34|OwnerIndex=519|IndexInSheet=-1|OwnerPartId=-1|Location.X=201|Location.Y=827|Color=8388608|FontID=1|Text=C58|Name=Designator|ReadOnlyState=1
|RECORD=41|OwnerIndex=519|IndexInSheet=-1|OwnerPartId=1|Location.X=201|Location.Y=817|Color=8388608|FontID=1|Text=10uF|Name=Comment
|RECORD=44|OwnerIndex=519
|RECORD=45|OwnerIndex=555|IndexInSheet=-1|UseComponentLibrary=T|ModelName=FP-MK212BG-MFG|ModelType=PCBLIB|DatafileCount=1|ModelDatafileEntity0=FP-MK212BG-MFG|ModelDatafileKind0=PCBLib|IsCurrent=T|DatalinksLocked=T|DatabaseDatalinksLocked=T
|RECORD=46|OwnerIndex=556
|RECORD=48|OwnerIndex=556
|RECORD=45|OwnerIndex=555|IndexInSheet=-1|UseComponentLibrary=T|ModelName=FP-MK212BG-IPC_C|ModelType=PCBLIB|DatafileCount=1|ModelDatafileEntity0=FP-MK212BG-IPC_C|ModelDatafileKind0=PCBLib|DatalinksLocked=T|DatabaseDatalinksLocked=T
|RECORD=46|OwnerIndex=559
|RECORD=48|OwnerIndex=559
|RECORD=45|OwnerIndex=555|IndexInSheet=-1|UseComponentLibrary=T|ModelName=FP-MK212BG-IPC_B|ModelType=PCBLIB|DatafileCount=1|ModelDatafileEntity0=FP-MK212BG-IPC_B|ModelDatafileKind0=PCBLib|DatalinksLocked=T|DatabaseDatalinksLocked=T
|RECORD=46|OwnerIndex=562
|RECORD=48|OwnerIndex=562
|RECORD=45|OwnerIndex=555|IndexInSheet=-1|UseComponentLibrary=T|ModelName=FP-MK212BG-IPC_A|ModelType=PCBLIB|DatafileCount=1|ModelDatafileEntity0=FP-MK212BG-IPC_A|ModelDatafileKind0=PCBLib|DatalinksLocked=T|DatabaseDatalinksLocked=T
|RECORD=46|OwnerIndex=565
|RECORD=48|OwnerIndex=565
|RECORD=45|OwnerIndex=555|IndexInSheet=-1|UseComponentLibrary=T|ModelName=TMK212BBJ106_G-T|ModelType=SIM|IsCurrent=T|DatalinksLocked=T|DatabaseDatalinksLocked=T
|RECORD=46|OwnerIndex=568
|RECORD=48|OwnerIndex=568
|RECORD=41|OwnerIndex=570|IndexInSheet=-1|OwnerPartId=-1|Color=8388608|FontID=1|IsHidden=T|Text=General|Name=Kind
|RECORD=41|OwnerIndex=570|IndexInSheet=-1|OwnerPartId=-1|Color=8388608|FontID=1|IsHidden=T|Text=Spice Subcircuit|Name=SubKind
|RECORD=41|OwnerIndex=570|IndexInSheet=-1|OwnerPartId=-1|Color=8388608|FontID=1|IsHidden=T|Name=Spice Prefix
|RECORD=41|OwnerIndex=570|IndexInSheet=-1|OwnerPartId=-1|Color=8388608|FontID=1|IsHidden=T|Name=Excluded Parts
|RECORD=41|OwnerIndex=570|IndexInSheet=-1|OwnerPartId=-1|Color=8388608|FontID=1|IsHidden=T|Name=Netlist
|RECORD=1|LibReference=b4654b650e69147ec39a6b967a45e02|ComponentDescription=None|PartCount=2|DisplayModeCount=1|IndexInSheet=60|OwnerPartId=-1|Location.X=290|Location.Y=840|CurrentPartId=1|LibraryPath=*|SourceLibraryName=Altium Content Vault|TargetFileName=*|AreaColor=11599871|Color=128|PartIDLocked=T|DesignItemId=CMP-14477-000079-2|AllPinCount=2
|RECORD=2|OwnerIndex=576|OwnerPartId=1|Electrical=4|PinConglomerate=49|PinLength=7|Location.X=290|Location.Y=833|Name=1|Designator=1|PinPropagationDelay=0.000000E+000
|RECORD=2|OwnerIndex=576|OwnerPartId=1|Electrical=4|PinConglomerate=51|PinLength=6|Location.X=290|Location.Y=826|Name=2|Designator=2|PinPropagationDelay=0.000000E+000
|RECORD=13|OwnerIndex=576|IsNotAccesible=T|IndexInSheet=2|OwnerPartId=1|Location.X=300|Location.Y=833|Corner.X=280|Corner.Y=833|LineWidth=1|Color=16711680
|RECORD=13|OwnerIndex=576|IsNotAccesible=T|IndexInSheet=3|OwnerPartId=1|Location.X=300|Location.Y=827|Corner.X=280|Corner.Y=827|LineWidth=1|Color=16711680
|RECORD=13|OwnerIndex=576|IsNotAccesible=T|IndexInSheet=4|OwnerPartId=1|Location.X=290|Location.Y=833|Corner.X=290|Corner.Y=836|LineWidth=1|Color=16711680
|RECORD=13|OwnerIndex=576|IsNotAccesible=T|IndexInSheet=5|OwnerPartId=1|Location.X=290|Location.Y=826|Corner.X=290|Corner.Y=825|LineWidth=1|Color=16711680
|RECORD=41|OwnerIndex=576|IndexInSheet=6|OwnerPartId=-1|Location.X=279|Location.Y=842|Color=8388608|FontID=1|IsHidden=T|Text=Tape and Reel|Name=Packaging
|RECORD=41|OwnerIndex=576|IndexInSheet=7|OwnerPartId=-1|Location.X=279|Location.Y=842|Color=8388608|FontID=1|IsHidden=T|Text=10uF|Name=Capacitance
|RECORD=41|OwnerIndex=576|IndexInSheet=8|OwnerPartId=-1|Location.X=279|Location.Y=842|Color=8388608|FontID=1|IsHidden=T|Text=25V|Name=Voltage Rating (DC)
|RECORD=41|OwnerIndex=576|IndexInSheet=9|OwnerPartId=-1|Location.X=279|Location.Y=842|Color=8388608|FontID=1|IsHidden=T|Text=0.053inch|Name=Thickness
|RECORD=41|OwnerIndex=576|IndexInSheet=10|OwnerPartId=-1|Location.X=279|Location.Y=842|Color=8388608|FontID=1|IsHidden=T|Text=Ceramic|Name=Resistor Type
|RECORD=41|OwnerIndex=576|IndexInSheet=11|OwnerPartId=-1|Location.X=279|Location.Y=842|Color=8388608|FontID=1|IsHidden=T|Text=Yes|Name=RoHS Compliant
|RECORD=41|OwnerIndex=576|IndexInSheet=12|OwnerPartId=-1|Location.X=279|Location.Y=842|Color=8388608|FontID=1|IsHidden=T|Text=Lead Free|Name=Lead Free
|RECORD=41|OwnerIndex=576|IndexInSheet=13|OwnerPartId=-1|Location.X=279|Location.Y=842|Color=8388608|FontID=1|IsHidden=T|Text=No SVHC|Name=REACH SVHC
|RECORD=41|OwnerIndex=576|IndexInSheet=14|OwnerPartId=-1|Location.X=279|Location.Y=842|Color=8388608|FontID=1|IsHidden=T|Text=2|Name=Number of Pins
|RECORD=41|OwnerIndex=576|IndexInSheet=15|OwnerPartId=-1|Location.X=279|Location.Y=842|Color=8388608|FontID=1|IsHidden=T|Text=1|Name=Package Quantity
|RECORD=41|OwnerIndex=576|IndexInSheet=16|OwnerPartId=-1|Location.X=279|Location.Y=842|Color=8388608|FontID=1|IsHidden=T|Text=Surface Mount|Name=Mount
|RECORD=41|OwnerIndex=576|IndexInSheet=17|OwnerPartId=-1|Location.X=279|Location.Y=842|Color=8388608|FontID=1|IsHidden=T|Text=SMD/SMT|Name=Termination
|RECORD=41|OwnerIndex=576|IndexInSheet=18|OwnerPartId=-1|Location.X=279|Location.Y=842|Color=8388608|FontID=1|IsHidden=T|Text=0.049inch|Name=Width
|RECORD=41|OwnerIndex=576|IndexInSheet=19|OwnerPartId=-1|Location.X=279|Location.Y=842|Color=8388608|FontID=1|IsHidden=T|Text=85°C|Name=Max Operating Temperature
|RECORD=41|OwnerIndex=576|IndexInSheet=20|OwnerPartId=-1|Location.X=279|Location.Y=842|Color=8388608|FontID=1|IsHidden=T|Text=0.079inch|Name=Length
|RECORD=41|OwnerIndex=576|IndexInSheet=21|OwnerPartId=-1|Location.X=279|Location.Y=842|Color=8388608|FontID=1|IsHidden=T|Text=0805|Name=Case/Package
|RECORD=41|OwnerIndex=576|IndexInSheet=22|OwnerPartId=-1|Location.X=279|Location.Y=842|Color=8388608|FontID=1|IsHidden=T|Text=25V|Name=Voltage Rating
|RECORD=41|OwnerIndex=576|IndexInSheet=23|OwnerPartId=-1|Location.X=279|Location.Y=842|Color=8388608|FontID=1|IsHidden=T|Text=-55°C|Name=Min Operating Temperature
|RECORD=41|OwnerIndex=576|IndexInSheet=24|OwnerPartId=-1|Location.X=279|Location.Y=842|Color=8388608|FontID=1|IsHidden=T|Text=10%|Name=Tolerance
|RECORD=41|OwnerIndex=576|IndexInSheet=25|OwnerPartId=-1|Location.X=279|Location.Y=842|Color=8388608|FontID=1|IsHidden=T|Text=X7R|Name=Dielectric
|RECORD=41|OwnerIndex=576|IndexInSheet=26|OwnerPartId=-1|Location.X=279|Location.Y=842|Color=8388608|FontID=1|IsHidden=T|Text=2012|Name=Case Code (Metric)
|RECORD=41|OwnerIndex=576|IndexInSheet=27|OwnerPartId=-1|Location.X=279|Location.Y=842|Color=8388608|FontID=1|IsHidden=T|Text=0805|Name=Case Code (Imperial)
|RECORD=41|OwnerIndex=576|IndexInSheet=28|OwnerPartId=-1|Location.X=279|Location.Y=842|Color=8388608|FontID=1|IsHidden=T|Text=1.25mm|Name=Height
|RECORD=41|OwnerIndex=576|IndexInSheet=29|OwnerPartId=-1|Location.X=279|Location.Y=842|Color=8388608|FontID=1|IsHidden=T|Text=16V|Name=Voltage
|RECORD=41|OwnerIndex=576|IndexInSheet=30|OwnerPartId=-1|Location.X=279|Location.Y=842|Color=8388608|FontID=1|IsHidden=T|Text=M|Name=Series
|RECORD=34|OwnerIndex=576|IndexInSheet=-1|OwnerPartId=-1|Location.X=301|Location.Y=827|Color=8388608|FontID=1|Text=C60|Name=Designator|ReadOnlyState=1
|RECORD=41|OwnerIndex=576|IndexInSheet=-1|OwnerPartId=1|Location.X=301|Location.Y=817|Color=8388608|FontID=1|Text=10uF|Name=Comment
|RECORD=44|OwnerIndex=576
|RECORD=45|OwnerIndex=612|IndexInSheet=-1|UseComponentLibrary=T|ModelName=FP-MK212BG-MFG|ModelType=PCBLIB|DatafileCount=1|ModelDatafileEntity0=FP-MK212BG-MFG|ModelDatafileKind0=PCBLib|IsCurrent=T|DatalinksLocked=T|DatabaseDatalinksLocked=T
|RECORD=46|OwnerIndex=613
|RECORD=48|OwnerIndex=613
|RECORD=45|OwnerIndex=612|IndexInSheet=-1|UseComponentLibrary=T|ModelName=FP-MK212BG-IPC_C|ModelType=PCBLIB|DatafileCount=1|ModelDatafileEntity0=FP-MK212BG-IPC_C|ModelDatafileKind0=PCBLib|DatalinksLocked=T|DatabaseDatalinksLocked=T
|RECORD=46|OwnerIndex=616
|RECORD=48|OwnerIndex=616
|RECORD=45|OwnerIndex=612|IndexInSheet=-1|UseComponentLibrary=T|ModelName=FP-MK212BG-IPC_B|ModelType=PCBLIB|DatafileCount=1|ModelDatafileEntity0=FP-MK212BG-IPC_B|ModelDatafileKind0=PCBLib|DatalinksLocked=T|DatabaseDatalinksLocked=T
|RECORD=46|OwnerIndex=619
|RECORD=48|OwnerIndex=619
|RECORD=45|OwnerIndex=612|IndexInSheet=-1|UseComponentLibrary=T|ModelName=FP-MK212BG-IPC_A|ModelType=PCBLIB|DatafileCount=1|ModelDatafileEntity0=FP-MK212BG-IPC_A|ModelDatafileKind0=PCBLib|DatalinksLocked=T|DatabaseDatalinksLocked=T
|RECORD=46|OwnerIndex=622
|RECORD=48|OwnerIndex=622
|RECORD=45|OwnerIndex=612|IndexInSheet=-1|UseComponentLibrary=T|ModelName=TMK212BBJ106_G-T|ModelType=SIM|IsCurrent=T|DatalinksLocked=T|DatabaseDatalinksLocked=T
|RECORD=46|OwnerIndex=625
|RECORD=48|OwnerIndex=625
|RECORD=41|OwnerIndex=627|IndexInSheet=-1|OwnerPartId=-1|Color=8388608|FontID=1|IsHidden=T|Text=General|Name=Kind
|RECORD=41|OwnerIndex=627|IndexInSheet=-1|OwnerPartId=-1|Color=8388608|FontID=1|IsHidden=T|Text=Spice Subcircuit|Name=SubKind
|RECORD=41|OwnerIndex=627|IndexInSheet=-1|OwnerPartId=-1|Color=8388608|FontID=1|IsHidden=T|Name=Spice Prefix
|RECORD=41|OwnerIndex=627|IndexInSheet=-1|OwnerPartId=-1|Color=8388608|FontID=1|IsHidden=T|Name=Excluded Parts
|RECORD=41|OwnerIndex=627|IndexInSheet=-1|OwnerPartId=-1|Color=8388608|FontID=1|IsHidden=T|Name=Netlist
|RECORD=1|LibReference=b4654b650e69147ec39a6b967a45e02|ComponentDescription=None|PartCount=2|DisplayModeCount=1|IndexInSheet=61|OwnerPartId=-1|Location.X=80|Location.Y=630|CurrentPartId=1|LibraryPath=*|SourceLibraryName=Altium Content Vault|TargetFileName=*|AreaColor=11599871|Color=128|PartIDLocked=T|DesignItemId=CMP-14477-000079-2|AllPinCount=2
|RECORD=2|OwnerIndex=633|OwnerPartId=1|Electrical=4|PinConglomerate=49|PinLength=7|Location.X=80|Location.Y=623|Name=1|Designator=1|PinPropagationDelay=0.000000E+000
|RECORD=2|OwnerIndex=633|OwnerPartId=1|Electrical=4|PinConglomerate=51|PinLength=6|Location.X=80|Location.Y=616|Name=2|Designator=2|PinPropagationDelay=0.000000E+000
|RECORD=13|OwnerIndex=633|IsNotAccesible=T|IndexInSheet=2|OwnerPartId=1|Location.X=90|Location.Y=623|Corner.X=70|Corner.Y=623|LineWidth=1|Color=16711680
|RECORD=13|OwnerIndex=633|IsNotAccesible=T|IndexInSheet=3|OwnerPartId=1|Location.X=90|Location.Y=617|Corner.X=70|Corner.Y=617|LineWidth=1|Color=16711680
|RECORD=13|OwnerIndex=633|IsNotAccesible=T|IndexInSheet=4|OwnerPartId=1|Location.X=80|Location.Y=623|Corner.X=80|Corner.Y=626|LineWidth=1|Color=16711680
|RECORD=13|OwnerIndex=633|IsNotAccesible=T|IndexInSheet=5|OwnerPartId=1|Location.X=80|Location.Y=616|Corner.X=80|Corner.Y=615|LineWidth=1|Color=16711680
|RECORD=41|OwnerIndex=633|IndexInSheet=6|OwnerPartId=-1|Location.X=69|Location.Y=632|Color=8388608|FontID=1|IsHidden=T|Text=Tape and Reel|Name=Packaging
|RECORD=41|OwnerIndex=633|IndexInSheet=7|OwnerPartId=-1|Location.X=69|Location.Y=632|Color=8388608|FontID=1|IsHidden=T|Text=10uF|Name=Capacitance
|RECORD=41|OwnerIndex=633|IndexInSheet=8|OwnerPartId=-1|Location.X=69|Location.Y=632|Color=8388608|FontID=1|IsHidden=T|Text=25V|Name=Voltage Rating (DC)
|RECORD=41|OwnerIndex=633|IndexInSheet=9|OwnerPartId=-1|Location.X=69|Location.Y=632|Color=8388608|FontID=1|IsHidden=T|Text=0.053inch|Name=Thickness
|RECORD=41|OwnerIndex=633|IndexInSheet=10|OwnerPartId=-1|Location.X=69|Location.Y=632|Color=8388608|FontID=1|IsHidden=T|Text=Ceramic|Name=Resistor Type
|RECORD=41|OwnerIndex=633|IndexInSheet=11|OwnerPartId=-1|Location.X=69|Location.Y=632|Color=8388608|FontID=1|IsHidden=T|Text=Yes|Name=RoHS Compliant
|RECORD=41|OwnerIndex=633|IndexInSheet=12|OwnerPartId=-1|Location.X=69|Location.Y=632|Color=8388608|FontID=1|IsHidden=T|Text=Lead Free|Name=Lead Free
|RECORD=41|OwnerIndex=633|IndexInSheet=13|OwnerPartId=-1|Location.X=69|Location.Y=632|Color=8388608|FontID=1|IsHidden=T|Text=No SVHC|Name=REACH SVHC
|RECORD=41|OwnerIndex=633|IndexInSheet=14|OwnerPartId=-1|Location.X=69|Location.Y=632|Color=8388608|FontID=1|IsHidden=T|Text=2|Name=Number of Pins
|RECORD=41|OwnerIndex=633|IndexInSheet=15|OwnerPartId=-1|Location.X=69|Location.Y=632|Color=8388608|FontID=1|IsHidden=T|Text=1|Name=Package Quantity
|RECORD=41|OwnerIndex=633|IndexInSheet=16|OwnerPartId=-1|Location.X=69|Location.Y=632|Color=8388608|FontID=1|IsHidden=T|Text=Surface Mount|Name=Mount
|RECORD=41|OwnerIndex=633|IndexInSheet=17|OwnerPartId=-1|Location.X=69|Location.Y=632|Color=8388608|FontID=1|IsHidden=T|Text=SMD/SMT|Name=Termination
|RECORD=41|OwnerIndex=633|IndexInSheet=18|OwnerPartId=-1|Location.X=69|Location.Y=632|Color=8388608|FontID=1|IsHidden=T|Text=0.049inch|Name=Width
|RECORD=41|OwnerIndex=633|IndexInSheet=19|OwnerPartId=-1|Location.X=69|Location.Y=632|Color=8388608|FontID=1|IsHidden=T|Text=85°C|Name=Max Operating Temperature
|RECORD=41|OwnerIndex=633|IndexInSheet=20|OwnerPartId=-1|Location.X=69|Location.Y=632|Color=8388608|FontID=1|IsHidden=T|Text=0.079inch|Name=Length
|RECORD=41|OwnerIndex=633|IndexInSheet=21|OwnerPartId=-1|Location.X=69|Location.Y=632|Color=8388608|FontID=1|IsHidden=T|Text=0805|Name=Case/Package
|RECORD=41|OwnerIndex=633|IndexInSheet=22|OwnerPartId=-1|Location.X=69|Location.Y=632|Color=8388608|FontID=1|IsHidden=T|Text=25V|Name=Voltage Rating
|RECORD=41|OwnerIndex=633|IndexInSheet=23|OwnerPartId=-1|Location.X=69|Location.Y=632|Color=8388608|FontID=1|IsHidden=T|Text=-55°C|Name=Min Operating Temperature
|RECORD=41|OwnerIndex=633|IndexInSheet=24|OwnerPartId=-1|Location.X=69|Location.Y=632|Color=8388608|FontID=1|IsHidden=T|Text=10%|Name=Tolerance
|RECORD=41|OwnerIndex=633|IndexInSheet=25|OwnerPartId=-1|Location.X=69|Location.Y=632|Color=8388608|FontID=1|IsHidden=T|Text=X7R|Name=Dielectric
|RECORD=41|OwnerIndex=633|IndexInSheet=26|OwnerPartId=-1|Location.X=69|Location.Y=632|Color=8388608|FontID=1|IsHidden=T|Text=2012|Name=Case Code (Metric)
|RECORD=41|OwnerIndex=633|IndexInSheet=27|OwnerPartId=-1|Location.X=69|Location.Y=632|Color=8388608|FontID=1|IsHidden=T|Text=0805|Name=Case Code (Imperial)
|RECORD=41|OwnerIndex=633|IndexInSheet=28|OwnerPartId=-1|Location.X=69|Location.Y=632|Color=8388608|FontID=1|IsHidden=T|Text=1.25mm|Name=Height
|RECORD=41|OwnerIndex=633|IndexInSheet=29|OwnerPartId=-1|Location.X=69|Location.Y=632|Color=8388608|FontID=1|IsHidden=T|Text=16V|Name=Voltage
|RECORD=41|OwnerIndex=633|IndexInSheet=30|OwnerPartId=-1|Location.X=69|Location.Y=632|Color=8388608|FontID=1|IsHidden=T|Text=M|Name=Series
|RECORD=34|OwnerIndex=633|IndexInSheet=-1|OwnerPartId=-1|Location.X=91|Location.Y=617|Color=8388608|FontID=1|Text=C34|Name=Designator|ReadOnlyState=1
|RECORD=41|OwnerIndex=633|IndexInSheet=-1|OwnerPartId=1|Location.X=91|Location.Y=607|Color=8388608|FontID=1|Text=10uF|Name=Comment
|RECORD=44|OwnerIndex=633
|RECORD=45|OwnerIndex=669|IndexInSheet=-1|UseComponentLibrary=T|ModelName=FP-MK212BG-MFG|ModelType=PCBLIB|DatafileCount=1|ModelDatafileEntity0=FP-MK212BG-MFG|ModelDatafileKind0=PCBLib|IsCurrent=T|DatalinksLocked=T|DatabaseDatalinksLocked=T
|RECORD=46|OwnerIndex=670
|RECORD=48|OwnerIndex=670
|RECORD=45|OwnerIndex=669|IndexInSheet=-1|UseComponentLibrary=T|ModelName=FP-MK212BG-IPC_C|ModelType=PCBLIB|DatafileCount=1|ModelDatafileEntity0=FP-MK212BG-IPC_C|ModelDatafileKind0=PCBLib|DatalinksLocked=T|DatabaseDatalinksLocked=T
|RECORD=46|OwnerIndex=673
|RECORD=48|OwnerIndex=673
|RECORD=45|OwnerIndex=669|IndexInSheet=-1|UseComponentLibrary=T|ModelName=FP-MK212BG-IPC_B|ModelType=PCBLIB|DatafileCount=1|ModelDatafileEntity0=FP-MK212BG-IPC_B|ModelDatafileKind0=PCBLib|DatalinksLocked=T|DatabaseDatalinksLocked=T
|RECORD=46|OwnerIndex=676
|RECORD=48|OwnerIndex=676
|RECORD=45|OwnerIndex=669|IndexInSheet=-1|UseComponentLibrary=T|ModelName=FP-MK212BG-IPC_A|ModelType=PCBLIB|DatafileCount=1|ModelDatafileEntity0=FP-MK212BG-IPC_A|ModelDatafileKind0=PCBLib|DatalinksLocked=T|DatabaseDatalinksLocked=T
|RECORD=46|OwnerIndex=679
|RECORD=48|OwnerIndex=679
|RECORD=45|OwnerIndex=669|IndexInSheet=-1|UseComponentLibrary=T|ModelName=TMK212BBJ106_G-T|ModelType=SIM|IsCurrent=T|DatalinksLocked=T|DatabaseDatalinksLocked=T
|RECORD=46|OwnerIndex=682
|RECORD=48|OwnerIndex=682
|RECORD=41|OwnerIndex=684|IndexInSheet=-1|OwnerPartId=-1|Color=8388608|FontID=1|IsHidden=T|Text=General|Name=Kind
|RECORD=41|OwnerIndex=684|IndexInSheet=-1|OwnerPartId=-1|Color=8388608|FontID=1|IsHidden=T|Text=Spice Subcircuit|Name=SubKind
|RECORD=41|OwnerIndex=684|IndexInSheet=-1|OwnerPartId=-1|Color=8388608|FontID=1|IsHidden=T|Name=Spice Prefix
|RECORD=41|OwnerIndex=684|IndexInSheet=-1|OwnerPartId=-1|Color=8388608|FontID=1|IsHidden=T|Name=Excluded Parts
|RECORD=41|OwnerIndex=684|IndexInSheet=-1|OwnerPartId=-1|Color=8388608|FontID=1|IsHidden=T|Name=Netlist
|RECORD=1|LibReference=b4654b650e69147ec39a6b967a45e02|ComponentDescription=None|PartCount=2|DisplayModeCount=1|IndexInSheet=62|OwnerPartId=-1|Location.X=180|Location.Y=630|CurrentPartId=1|LibraryPath=*|SourceLibraryName=Altium Content Vault|TargetFileName=*|AreaColor=11599871|Color=128|PartIDLocked=T|DesignItemId=CMP-14477-000079-2|AllPinCount=2
|RECORD=2|OwnerIndex=690|OwnerPartId=1|Electrical=4|PinConglomerate=49|PinLength=7|Location.X=180|Location.Y=623|Name=1|Designator=1|PinPropagationDelay=0.000000E+000
|RECORD=2|OwnerIndex=690|OwnerPartId=1|Electrical=4|PinConglomerate=51|PinLength=6|Location.X=180|Location.Y=616|Name=2|Designator=2|PinPropagationDelay=0.000000E+000
|RECORD=13|OwnerIndex=690|IsNotAccesible=T|IndexInSheet=2|OwnerPartId=1|Location.X=190|Location.Y=623|Corner.X=170|Corner.Y=623|LineWidth=1|Color=16711680
|RECORD=13|OwnerIndex=690|IsNotAccesible=T|IndexInSheet=3|OwnerPartId=1|Location.X=190|Location.Y=617|Corner.X=170|Corner.Y=617|LineWidth=1|Color=16711680
|RECORD=13|OwnerIndex=690|IsNotAccesible=T|IndexInSheet=4|OwnerPartId=1|Location.X=180|Location.Y=623|Corner.X=180|Corner.Y=626|LineWidth=1|Color=16711680
|RECORD=13|OwnerIndex=690|IsNotAccesible=T|IndexInSheet=5|OwnerPartId=1|Location.X=180|Location.Y=616|Corner.X=180|Corner.Y=615|LineWidth=1|Color=16711680
|RECORD=41|OwnerIndex=690|IndexInSheet=6|OwnerPartId=-1|Location.X=169|Location.Y=632|Color=8388608|FontID=1|IsHidden=T|Text=Tape and Reel|Name=Packaging
|RECORD=41|OwnerIndex=690|IndexInSheet=7|OwnerPartId=-1|Location.X=169|Location.Y=632|Color=8388608|FontID=1|IsHidden=T|Text=10uF|Name=Capacitance
|RECORD=41|OwnerIndex=690|IndexInSheet=8|OwnerPartId=-1|Location.X=169|Location.Y=632|Color=8388608|FontID=1|IsHidden=T|Text=25V|Name=Voltage Rating (DC)
|RECORD=41|OwnerIndex=690|IndexInSheet=9|OwnerPartId=-1|Location.X=169|Location.Y=632|Color=8388608|FontID=1|IsHidden=T|Text=0.053inch|Name=Thickness
|RECORD=41|OwnerIndex=690|IndexInSheet=10|OwnerPartId=-1|Location.X=169|Location.Y=632|Color=8388608|FontID=1|IsHidden=T|Text=Ceramic|Name=Resistor Type
|RECORD=41|OwnerIndex=690|IndexInSheet=11|OwnerPartId=-1|Location.X=169|Location.Y=632|Color=8388608|FontID=1|IsHidden=T|Text=Yes|Name=RoHS Compliant
|RECORD=41|OwnerIndex=690|IndexInSheet=12|OwnerPartId=-1|Location.X=169|Location.Y=632|Color=8388608|FontID=1|IsHidden=T|Text=Lead Free|Name=Lead Free
|RECORD=41|OwnerIndex=690|IndexInSheet=13|OwnerPartId=-1|Location.X=169|Location.Y=632|Color=8388608|FontID=1|IsHidden=T|Text=No SVHC|Name=REACH SVHC
|RECORD=41|OwnerIndex=690|IndexInSheet=14|OwnerPartId=-1|Location.X=169|Location.Y=632|Color=8388608|FontID=1|IsHidden=T|Text=2|Name=Number of Pins
|RECORD=41|OwnerIndex=690|IndexInSheet=15|OwnerPartId=-1|Location.X=169|Location.Y=632|Color=8388608|FontID=1|IsHidden=T|Text=1|Name=Package Quantity
|RECORD=41|OwnerIndex=690|IndexInSheet=16|OwnerPartId=-1|Location.X=169|Location.Y=632|Color=8388608|FontID=1|IsHidden=T|Text=Surface Mount|Name=Mount
|RECORD=41|OwnerIndex=690|IndexInSheet=17|OwnerPartId=-1|Location.X=169|Location.Y=632|Color=8388608|FontID=1|IsHidden=T|Text=SMD/SMT|Name=Termination
|RECORD=41|OwnerIndex=690|IndexInSheet=18|OwnerPartId=-1|Location.X=169|Location.Y=632|Color=8388608|FontID=1|IsHidden=T|Text=0.049inch|Name=Width
|RECORD=41|OwnerIndex=690|IndexInSheet=19|OwnerPartId=-1|Location.X=169|Location.Y=632|Color=8388608|FontID=1|IsHidden=T|Text=85°C|Name=Max Operating Temperature
|RECORD=41|OwnerIndex=690|IndexInSheet=20|OwnerPartId=-1|Location.X=169|Location.Y=632|Color=8388608|FontID=1|IsHidden=T|Text=0.079inch|Name=Length
|RECORD=41|OwnerIndex=690|IndexInSheet=21|OwnerPartId=-1|Location.X=169|Location.Y=632|Color=8388608|FontID=1|IsHidden=T|Text=0805|Name=Case/Package
|RECORD=41|OwnerIndex=690|IndexInSheet=22|OwnerPartId=-1|Location.X=169|Location.Y=632|Color=8388608|FontID=1|IsHidden=T|Text=25V|Name=Voltage Rating
|RECORD=41|OwnerIndex=690|IndexInSheet=23|OwnerPartId=-1|Location.X=169|Location.Y=632|Color=8388608|FontID=1|IsHidden=T|Text=-55°C|Name=Min Operating Temperature
|RECORD=41|OwnerIndex=690|IndexInSheet=24|OwnerPartId=-1|Location.X=169|Location.Y=632|Color=8388608|FontID=1|IsHidden=T|Text=10%|Name=Tolerance
|RECORD=41|OwnerIndex=690|IndexInSheet=25|OwnerPartId=-1|Location.X=169|Location.Y=632|Color=8388608|FontID=1|IsHidden=T|Text=X7R|Name=Dielectric
|RECORD=41|OwnerIndex=690|IndexInSheet=26|OwnerPartId=-1|Location.X=169|Location.Y=632|Color=8388608|FontID=1|IsHidden=T|Text=2012|Name=Case Code (Metric)
|RECORD=41|OwnerIndex=690|IndexInSheet=27|OwnerPartId=-1|Location.X=169|Location.Y=632|Color=8388608|FontID=1|IsHidden=T|Text=0805|Name=Case Code (Imperial)
|RECORD=41|OwnerIndex=690|IndexInSheet=28|OwnerPartId=-1|Location.X=169|Location.Y=632|Color=8388608|FontID=1|IsHidden=T|Text=1.25mm|Name=Height
|RECORD=41|OwnerIndex=690|IndexInSheet=29|OwnerPartId=-1|Location.X=169|Location.Y=632|Color=8388608|FontID=1|IsHidden=T|Text=16V|Name=Voltage
|RECORD=41|OwnerIndex=690|IndexInSheet=30|OwnerPartId=-1|Location.X=169|Location.Y=632|Color=8388608|FontID=1|IsHidden=T|Text=M|Name=Series
|RECORD=34|OwnerIndex=690|IndexInSheet=-1|OwnerPartId=-1|Location.X=191|Location.Y=617|Color=8388608|FontID=1|Text=C35|Name=Designator|ReadOnlyState=1
|RECORD=41|OwnerIndex=690|IndexInSheet=-1|OwnerPartId=1|Location.X=191|Location.Y=607|Color=8388608|FontID=1|Text=10uF|Name=Comment
|RECORD=44|OwnerIndex=690
|RECORD=45|OwnerIndex=726|IndexInSheet=-1|UseComponentLibrary=T|ModelName=FP-MK212BG-MFG|ModelType=PCBLIB|DatafileCount=1|ModelDatafileEntity0=FP-MK212BG-MFG|ModelDatafileKind0=PCBLib|IsCurrent=T|DatalinksLocked=T|DatabaseDatalinksLocked=T
|RECORD=46|OwnerIndex=727
|RECORD=48|OwnerIndex=727
|RECORD=45|OwnerIndex=726|IndexInSheet=-1|UseComponentLibrary=T|ModelName=FP-MK212BG-IPC_C|ModelType=PCBLIB|DatafileCount=1|ModelDatafileEntity0=FP-MK212BG-IPC_C|ModelDatafileKind0=PCBLib|DatalinksLocked=T|DatabaseDatalinksLocked=T
|RECORD=46|OwnerIndex=730
|RECORD=48|OwnerIndex=730
|RECORD=45|OwnerIndex=726|IndexInSheet=-1|UseComponentLibrary=T|ModelName=FP-MK212BG-IPC_B|ModelType=PCBLIB|DatafileCount=1|ModelDatafileEntity0=FP-MK212BG-IPC_B|ModelDatafileKind0=PCBLib|DatalinksLocked=T|DatabaseDatalinksLocked=T
|RECORD=46|OwnerIndex=733
|RECORD=48|OwnerIndex=733
|RECORD=45|OwnerIndex=726|IndexInSheet=-1|UseComponentLibrary=T|ModelName=FP-MK212BG-IPC_A|ModelType=PCBLIB|DatafileCount=1|ModelDatafileEntity0=FP-MK212BG-IPC_A|ModelDatafileKind0=PCBLib|DatalinksLocked=T|DatabaseDatalinksLocked=T
|RECORD=46|OwnerIndex=736
|RECORD=48|OwnerIndex=736
|RECORD=45|OwnerIndex=726|IndexInSheet=-1|UseComponentLibrary=T|ModelName=TMK212BBJ106_G-T|ModelType=SIM|IsCurrent=T|DatalinksLocked=T|DatabaseDatalinksLocked=T
|RECORD=46|OwnerIndex=739
|RECORD=48|OwnerIndex=739
|RECORD=41|OwnerIndex=741|IndexInSheet=-1|OwnerPartId=-1|Color=8388608|FontID=1|IsHidden=T|Text=General|Name=Kind
|RECORD=41|OwnerIndex=741|IndexInSheet=-1|OwnerPartId=-1|Color=8388608|FontID=1|IsHidden=T|Text=Spice Subcircuit|Name=SubKind
|RECORD=41|OwnerIndex=741|IndexInSheet=-1|OwnerPartId=-1|Color=8388608|FontID=1|IsHidden=T|Name=Spice Prefix
|RECORD=41|OwnerIndex=741|IndexInSheet=-1|OwnerPartId=-1|Color=8388608|FontID=1|IsHidden=T|Name=Excluded Parts
|RECORD=41|OwnerIndex=741|IndexInSheet=-1|OwnerPartId=-1|Color=8388608|FontID=1|IsHidden=T|Name=Netlist
|RECORD=1|LibReference=Header 6X2A|ComponentDescription=Header, 6-Pin, Dual row|PartCount=2|DisplayModeCount=1|IndexInSheet=63|OwnerPartId=-1|Location.X=200|Location.Y=160|CurrentPartId=1|SourceLibraryName=Miscellaneous Connectors.IntLib|TargetFileName=*|AreaColor=11599871|Color=128|PartIDLocked=F|DesignItemId=Header 6X2A|AllPinCount=12
|RECORD=14|OwnerIndex=747|IsNotAccesible=T|OwnerPartId=1|Location.X=200|Location.Y=90|Corner.X=240|Corner.Y=160|Color=128|AreaColor=11599871|IsSolid=T
|RECORD=2|OwnerIndex=747|OwnerPartId=1|FormalType=1|Electrical=4|PinConglomerate=42|PinLength=20|Location.X=200|Location.Y=150|Name=1|Designator=1|PinPropagationDelay=0.000000E+000
|RECORD=2|OwnerIndex=747|OwnerPartId=1|FormalType=1|Electrical=4|PinConglomerate=42|PinLength=20|Location.X=200|Location.Y=140|Name=2|Designator=2|PinPropagationDelay=0.000000E+000
|RECORD=2|OwnerIndex=747|OwnerPartId=1|FormalType=1|Electrical=4|PinConglomerate=42|PinLength=20|Location.X=200|Location.Y=130|Name=3|Designator=3|PinPropagationDelay=0.000000E+000
|RECORD=2|OwnerIndex=747|OwnerPartId=1|FormalType=1|Electrical=4|PinConglomerate=42|PinLength=20|Location.X=200|Location.Y=120|Name=4|Designator=4|PinPropagationDelay=0.000000E+000
|RECORD=2|OwnerIndex=747|OwnerPartId=1|FormalType=1|Electrical=4|PinConglomerate=42|PinLength=20|Location.X=200|Location.Y=110|Name=5|Designator=5|PinPropagationDelay=0.000000E+000
|RECORD=2|OwnerIndex=747|OwnerPartId=1|FormalType=1|Electrical=4|PinConglomerate=42|PinLength=20|Location.X=200|Location.Y=100|Name=6|Designator=6|PinPropagationDelay=0.000000E+000
|RECORD=2|OwnerIndex=747|OwnerPartId=1|FormalType=1|Electrical=4|PinConglomerate=40|PinLength=20|Location.X=240|Location.Y=150|Name=7|Designator=7|PinPropagationDelay=0.000000E+000
|RECORD=2|OwnerIndex=747|OwnerPartId=1|FormalType=1|Electrical=4|PinConglomerate=40|PinLength=20|Location.X=240|Location.Y=140|Name=8|Designator=8|PinPropagationDelay=0.000000E+000
|RECORD=2|OwnerIndex=747|OwnerPartId=1|FormalType=1|Electrical=4|PinConglomerate=40|PinLength=20|Location.X=240|Location.Y=130|Name=9|Designator=9|PinPropagationDelay=0.000000E+000
|RECORD=2|OwnerIndex=747|OwnerPartId=1|FormalType=1|Electrical=4|PinConglomerate=40|PinLength=20|Location.X=240|Location.Y=120|Name=10|Designator=10|PinPropagationDelay=0.000000E+000
|RECORD=2|OwnerIndex=747|OwnerPartId=1|FormalType=1|Electrical=4|PinConglomerate=40|PinLength=20|Location.X=240|Location.Y=110|Name=11|Designator=11|PinPropagationDelay=0.000000E+000
|RECORD=2|OwnerIndex=747|OwnerPartId=1|FormalType=1|Electrical=4|PinConglomerate=40|PinLength=20|Location.X=240|Location.Y=100|Name=12|Designator=12|PinPropagationDelay=0.000000E+000
|RECORD=41|OwnerIndex=747|IndexInSheet=13|OwnerPartId=-1|Location.X=200|Location.Y=160|Color=8388608|FontID=1|IsHidden=T|Text=17-Jul-2002|Name=LatestRevisionDate
|RECORD=41|OwnerIndex=747|IndexInSheet=14|OwnerPartId=-1|Location.X=200|Location.Y=160|Color=8388608|FontID=1|IsHidden=T|Text=Re-released for DXP Platform.|Name=LatestRevisionNote
|RECORD=41|OwnerIndex=747|IndexInSheet=15|OwnerPartId=-1|Location.X=200|Location.Y=160|Color=8388608|FontID=1|IsHidden=T|Text=Altium Limited|Name=Publisher
|RECORD=34|OwnerIndex=747|IndexInSheet=-1|OwnerPartId=-1|Location.X=200|Location.Y=160|Color=8388608|FontID=1|Text=P3|Name=Designator|ReadOnlyState=1
|RECORD=41|OwnerIndex=747|IndexInSheet=-1|OwnerPartId=-1|Location.X=200|Location.Y=80|Color=8388608|FontID=1|Text=EXT GPIO|Name=Comment|ReadOnlyState=1
|RECORD=44|OwnerIndex=747
|RECORD=45|OwnerIndex=778|IndexInSheet=-1|Description=Connector; Header; 6x2 Position|UseComponentLibrary=T|ModelName=HDR2X6_CEN|ModelType=PCBLIB|DatafileCount=1|ModelDatafileEntity0=HDR2X6_CEN|ModelDatafileKind0=PCBLib|IsCurrent=T|DatalinksLocked=T|DatabaseDatalinksLocked=T|IntegratedModel=T|DatabaseModel=T
|RECORD=46|OwnerIndex=779
|RECORD=48|OwnerIndex=779
|RECORD=45|OwnerIndex=778|IndexInSheet=-1|UseComponentLibrary=T|ModelName=Connector|ModelType=SI|IsCurrent=T|DatalinksLocked=T|DatabaseDatalinksLocked=T|IntegratedModel=T|DatabaseModel=T
|RECORD=46|OwnerIndex=782
|RECORD=48|OwnerIndex=782
|RECORD=41|OwnerIndex=784|IndexInSheet=-1|OwnerPartId=-1|Color=8388608|FontID=1|Text=Connector|Name=Type
|RECORD=41|OwnerIndex=784|IndexInSheet=-1|OwnerPartId=-1|Color=8388608|FontID=1|Name=Tech
|RECORD=17|IndexInSheet=64|OwnerPartId=-1|ShowNetName=T|Location.X=160|Location.Y=190|Orientation=1|Color=128|FontID=1|Text=+3.3V
|RECORD=17|IndexInSheet=65|OwnerPartId=-1|Style=4|ShowNetName=T|Location.X=300|Location.Y=70|Orientation=3|Color=128|FontID=1|Text=GND
|RECORD=17|IndexInSheet=66|OwnerPartId=-1|Style=4|ShowNetName=T|Location.X=140|Location.Y=70|Orientation=3|Color=128|FontID=1|Text=GND
|RECORD=17|IndexInSheet=67|OwnerPartId=-1|ShowNetName=T|Location.X=280|Location.Y=190|Orientation=1|Color=128|FontID=1|Text=+3.3V
|RECORD=17|IndexInSheet=68|OwnerPartId=-1|ShowNetName=T|Location.X=110|Location.Y=150|Orientation=2|Color=255|FontID=1|Text=EXT_GPIO_1|IsCrossSheetConnector=T
|RECORD=17|IndexInSheet=69|OwnerPartId=-1|ShowNetName=T|Location.X=110|Location.Y=140|Orientation=2|Color=255|FontID=1|Text=EXT_GPIO_2|IsCrossSheetConnector=T
|RECORD=17|IndexInSheet=70|OwnerPartId=-1|ShowNetName=T|Location.X=110|Location.Y=130|Orientation=2|Color=255|FontID=1|Text=EXT_GPIO_3|IsCrossSheetConnector=T
|RECORD=17|IndexInSheet=71|OwnerPartId=-1|ShowNetName=T|Location.X=110|Location.Y=120|Orientation=2|Color=255|FontID=1|Text=EXT_GPIO_4|IsCrossSheetConnector=T
|RECORD=17|IndexInSheet=72|OwnerPartId=-1|ShowNetName=T|Location.X=330|Location.Y=150|Color=255|FontID=1|Text=EXT_GPIO_7|IsCrossSheetConnector=T
|RECORD=17|IndexInSheet=73|OwnerPartId=-1|ShowNetName=T|Location.X=330|Location.Y=140|Color=255|FontID=1|Text=EXT_GPIO_8|IsCrossSheetConnector=T
|RECORD=17|IndexInSheet=74|OwnerPartId=-1|ShowNetName=T|Location.X=330|Location.Y=130|Color=255|FontID=1|Text=EXT_GPIO_9|IsCrossSheetConnector=T
|RECORD=17|IndexInSheet=75|OwnerPartId=-1|ShowNetName=T|Location.X=330|Location.Y=120|Color=255|FontID=1|Text=EXT_GPIO_10|IsCrossSheetConnector=T
|RECORD=4|IndexInSheet=76|OwnerPartId=-1|Location.X=150|Location.Y=220|Color=8388608|FontID=8|Text=EXTERNAL GPIO
|RECORD=41|IndexInSheet=77|OwnerPartId=-1|Color=8388608|FontID=1|IsHidden=T|Text=*|Name=CurrentTime|ReadOnlyState=1
|RECORD=41|IndexInSheet=78|OwnerPartId=-1|Color=8388608|FontID=1|IsHidden=T|Text=*|Name=CurrentDate|ReadOnlyState=1
|RECORD=41|IndexInSheet=79|OwnerPartId=-1|Color=8388608|FontID=1|IsHidden=T|Text=*|Name=Time|ReadOnlyState=1
|RECORD=41|IndexInSheet=80|OwnerPartId=-1|Color=8388608|FontID=1|IsHidden=T|Text=*|Name=Date|ReadOnlyState=1
|RECORD=41|IndexInSheet=81|OwnerPartId=-1|Color=8388608|FontID=1|IsHidden=T|Text=*|Name=DocumentFullPathAndName|ReadOnlyState=1
|RECORD=41|IndexInSheet=82|OwnerPartId=-1|Color=8388608|FontID=1|IsHidden=T|Text=*|Name=DocumentName|ReadOnlyState=1
|RECORD=41|IndexInSheet=83|OwnerPartId=-1|Color=8388608|FontID=1|IsHidden=T|Text=*|Name=ModifiedDate|ReadOnlyState=1
|RECORD=41|IndexInSheet=84|OwnerPartId=-1|Color=8388608|FontID=1|IsHidden=T|Text=*|Name=ApprovedBy|ReadOnlyState=1
|RECORD=41|IndexInSheet=85|OwnerPartId=-1|Color=8388608|FontID=1|IsHidden=T|Text=*|Name=CheckedBy|ReadOnlyState=1
|RECORD=41|IndexInSheet=86|OwnerPartId=-1|Color=8388608|FontID=1|IsHidden=T|Text=*|Name=Author|ReadOnlyState=1
|RECORD=41|IndexInSheet=87|OwnerPartId=-1|Color=8388608|FontID=1|IsHidden=T|Text=*|Name=CompanyName|ReadOnlyState=1
|RECORD=41|IndexInSheet=88|OwnerPartId=-1|Color=8388608|FontID=1|IsHidden=T|Text=*|Name=DrawnBy|ReadOnlyState=1
|RECORD=41|IndexInSheet=89|OwnerPartId=-1|Color=8388608|FontID=1|IsHidden=T|Text=*|Name=Engineer|ReadOnlyState=1
|RECORD=41|IndexInSheet=90|OwnerPartId=-1|Color=8388608|FontID=1|IsHidden=T|Text=*|Name=Organization|ReadOnlyState=1
|RECORD=41|IndexInSheet=91|OwnerPartId=-1|Color=8388608|FontID=1|IsHidden=T|Text=*|Name=Address1|ReadOnlyState=1
|RECORD=41|IndexInSheet=92|OwnerPartId=-1|Color=8388608|FontID=1|IsHidden=T|Text=*|Name=Address2|ReadOnlyState=1
|RECORD=41|IndexInSheet=93|OwnerPartId=-1|Color=8388608|FontID=1|IsHidden=T|Text=*|Name=Address3|ReadOnlyState=1
|RECORD=41|IndexInSheet=94|OwnerPartId=-1|Color=8388608|FontID=1|IsHidden=T|Text=*|Name=Address4|ReadOnlyState=1
|RECORD=41|IndexInSheet=95|OwnerPartId=-1|Color=8388608|FontID=1|IsHidden=T|Text=*|Name=Title|ReadOnlyState=1
|RECORD=41|IndexInSheet=96|OwnerPartId=-1|Color=8388608|FontID=1|IsHidden=T|Text=*|Name=DocumentNumber|ReadOnlyState=1
|RECORD=41|IndexInSheet=97|OwnerPartId=-1|Color=8388608|FontID=1|IsHidden=T|Text=*|Name=Revision|ReadOnlyState=1
|RECORD=41|IndexInSheet=98|OwnerPartId=-1|Color=8388608|FontID=1|IsHidden=T|Text=*|Name=SheetNumber|ReadOnlyState=1
|RECORD=41|IndexInSheet=99|OwnerPartId=-1|Color=8388608|FontID=1|IsHidden=T|Text=*|Name=SheetTotal|ReadOnlyState=1
|RECORD=41|IndexInSheet=100|OwnerPartId=-1|Color=8388608|FontID=1|IsHidden=T|Text=*|Name=Rule|ReadOnlyState=1
|RECORD=41|IndexInSheet=101|OwnerPartId=-1|Color=8388608|FontID=1|IsHidden=T|Text=*|Name=ImagePath|ReadOnlyState=1
|RECORD=41|IndexInSheet=102|OwnerPartId=-1|Color=8388608|FontID=1|IsHidden=T|Text=*|Name=ProjectName|ReadOnlyState=1
|RECORD=41|IndexInSheet=103|OwnerPartId=-1|Color=8388608|FontID=1|IsHidden=T|Text=*|Name=Application_BuildNumber|ReadOnlyState=1
|RECORD=1|LibReference=GNSS Standoff|PartCount=2|DisplayModeCount=1|IndexInSheet=104|OwnerPartId=-1|Location.X=1020|Location.Y=980|CurrentPartId=1|LibraryPath=*|SourceLibraryName=FPGA_CONN.SchLib|TargetFileName=*|AreaColor=11599871|Color=128|PartIDLocked=T|NotUseDBTableName=T|DesignItemId=GNSS Standoff
|RECORD=12|OwnerIndex=827|IsNotAccesible=T|OwnerPartId=1|Location.X=1020|Location.Y=980|Radius=9|Radius_Frac=45302|LineWidth=1|EndAngle=360.000|Color=16711680
|RECORD=41|OwnerIndex=827|IndexInSheet=1|OwnerPartId=-1|Location.X=1010|Location.X_Frac=54698|Location.Y=995|Color=8388608|FontID=1|IsHidden=T|Text=Digi-Key|Name=Supplier 1|ReadOnlyState=3
|RECORD=41|OwnerIndex=827|IndexInSheet=2|OwnerPartId=-1|Location.X=1010|Location.X_Frac=54698|Location.Y=950|Location.Y_Frac=54698|Color=8388608|FontID=1|Text=36-24393-ND|Name=Supplier Part Number 1|ReadOnlyState=3
|RECORD=34|OwnerIndex=827|IndexInSheet=-1|OwnerPartId=-1|Location.X=1010|Location.X_Frac=54698|Location.Y=989|Location.Y_Frac=45302|Color=8388608|FontID=1|Text=J5|Name=Designator|ReadOnlyState=1
|RECORD=41|OwnerIndex=827|IndexInSheet=-1|OwnerPartId=-1|Location.X=1010|Location.X_Frac=54698|Location.Y=960|Location.Y_Frac=54698|Color=8388608|FontID=1|Text=GNSS Standoff|Name=Comment
|RECORD=44|OwnerIndex=827
|RECORD=1|LibReference=GNSS Standoff|PartCount=2|DisplayModeCount=1|IndexInSheet=105|OwnerPartId=-1|Location.X=1020|Location.Y=930|CurrentPartId=1|LibraryPath=*|SourceLibraryName=FPGA_CONN.SchLib|TargetFileName=*|AreaColor=11599871|Color=128|PartIDLocked=T|NotUseDBTableName=T|DesignItemId=GNSS Standoff
|RECORD=12|OwnerIndex=834|IsNotAccesible=T|OwnerPartId=1|Location.X=1020|Location.Y=930|Radius=9|Radius_Frac=45302|LineWidth=1|EndAngle=360.000|Color=16711680
|RECORD=41|OwnerIndex=834|IndexInSheet=1|OwnerPartId=-1|Location.X=1010|Location.X_Frac=54698|Location.Y=945|Color=8388608|FontID=1|IsHidden=T|Text=Digi-Key|Name=Supplier 1|ReadOnlyState=3
|RECORD=41|OwnerIndex=834|IndexInSheet=2|OwnerPartId=-1|Location.X=1010|Location.X_Frac=54698|Location.Y=900|Location.Y_Frac=54698|Color=8388608|FontID=1|Text=36-24393-ND|Name=Supplier Part Number 1|ReadOnlyState=3
|RECORD=34|OwnerIndex=834|IndexInSheet=-1|OwnerPartId=-1|Location.X=1010|Location.X_Frac=54698|Location.Y=939|Location.Y_Frac=45302|Color=8388608|FontID=1|Text=J7|Name=Designator|ReadOnlyState=1
|RECORD=41|OwnerIndex=834|IndexInSheet=-1|OwnerPartId=-1|Location.X=1010|Location.X_Frac=54698|Location.Y=910|Location.Y_Frac=54698|Color=8388608|FontID=1|Text=GNSS Standoff|Name=Comment
|RECORD=44|OwnerIndex=834
|RECORD=1|LibReference=GNSS Standoff|PartCount=2|DisplayModeCount=1|IndexInSheet=106|OwnerPartId=-1|Location.X=1020|Location.Y=880|CurrentPartId=1|LibraryPath=*|SourceLibraryName=FPGA_CONN.SchLib|TargetFileName=*|AreaColor=11599871|Color=128|PartIDLocked=T|NotUseDBTableName=T|DesignItemId=GNSS Standoff
|RECORD=12|OwnerIndex=841|IsNotAccesible=T|OwnerPartId=1|Location.X=1020|Location.Y=880|Radius=9|Radius_Frac=45302|LineWidth=1|EndAngle=360.000|Color=16711680
|RECORD=41|OwnerIndex=841|IndexInSheet=1|OwnerPartId=-1|Location.X=1010|Location.X_Frac=54698|Location.Y=895|Color=8388608|FontID=1|IsHidden=T|Text=Digi-Key|Name=Supplier 1|ReadOnlyState=3
|RECORD=41|OwnerIndex=841|IndexInSheet=2|OwnerPartId=-1|Location.X=1010|Location.X_Frac=54698|Location.Y=850|Location.Y_Frac=54698|Color=8388608|FontID=1|Text=36-24393-ND|Name=Supplier Part Number 1|ReadOnlyState=3
|RECORD=34|OwnerIndex=841|IndexInSheet=-1|OwnerPartId=-1|Location.X=1010|Location.X_Frac=54698|Location.Y=889|Location.Y_Frac=45302|Color=8388608|FontID=1|Text=J8|Name=Designator|ReadOnlyState=1
|RECORD=41|OwnerIndex=841|IndexInSheet=-1|OwnerPartId=-1|Location.X=1010|Location.X_Frac=54698|Location.Y=860|Location.Y_Frac=54698|Color=8388608|FontID=1|Text=GNSS Standoff|Name=Comment
|RECORD=44|OwnerIndex=841
|RECORD=1|LibReference=GNSS Standoff|PartCount=2|DisplayModeCount=1|IndexInSheet=107|OwnerPartId=-1|Location.X=1020|Location.Y=830|CurrentPartId=1|LibraryPath=*|SourceLibraryName=FPGA_CONN.SchLib|TargetFileName=*|AreaColor=11599871|Color=128|PartIDLocked=T|NotUseDBTableName=T|DesignItemId=GNSS Standoff
|RECORD=12|OwnerIndex=848|IsNotAccesible=T|OwnerPartId=1|Location.X=1020|Location.Y=830|Radius=9|Radius_Frac=45302|LineWidth=1|EndAngle=360.000|Color=16711680
|RECORD=41|OwnerIndex=848|IndexInSheet=1|OwnerPartId=-1|Location.X=1010|Location.X_Frac=54698|Location.Y=845|Color=8388608|FontID=1|IsHidden=T|Text=Digi-Key|Name=Supplier 1|ReadOnlyState=3
|RECORD=41|OwnerIndex=848|IndexInSheet=2|OwnerPartId=-1|Location.X=1010|Location.X_Frac=54698|Location.Y=800|Location.Y_Frac=54698|Color=8388608|FontID=1|Text=36-24393-ND|Name=Supplier Part Number 1|ReadOnlyState=3
|RECORD=34|OwnerIndex=848|IndexInSheet=-1|OwnerPartId=-1|Location.X=1010|Location.X_Frac=54698|Location.Y=839|Location.Y_Frac=45302|Color=8388608|FontID=1|Text=J9|Name=Designator|ReadOnlyState=1
|RECORD=41|OwnerIndex=848|IndexInSheet=-1|OwnerPartId=-1|Location.X=1010|Location.X_Frac=54698|Location.Y=810|Location.Y_Frac=54698|Color=8388608|FontID=1|Text=GNSS Standoff|Name=Comment
|RECORD=44|OwnerIndex=848
|RECORD=1|LibReference=GNSS Standoff|PartCount=2|DisplayModeCount=1|IndexInSheet=108|OwnerPartId=-1|Location.X=790|Location.Y=640|CurrentPartId=1|LibraryPath=*|SourceLibraryName=FPGA_CONN.SchLib|TargetFileName=*|AreaColor=11599871|Color=128|PartIDLocked=T|NotUseDBTableName=T|DesignItemId=GNSS Standoff
|RECORD=12|OwnerIndex=855|IsNotAccesible=T|OwnerPartId=1|Location.X=790|Location.Y=640|Radius=9|Radius_Frac=45302|LineWidth=1|EndAngle=360.000|Color=16711680
|RECORD=41|OwnerIndex=855|IndexInSheet=1|OwnerPartId=-1|Location.X=780|Location.X_Frac=54698|Location.Y=655|Color=8388608|FontID=1|IsHidden=T|Text=Digi-Key|Name=Supplier 1|ReadOnlyState=3
|RECORD=41|OwnerIndex=855|IndexInSheet=2|OwnerPartId=-1|Location.X=780|Location.X_Frac=54698|Location.Y=610|Location.Y_Frac=54698|Color=8388608|FontID=1|Text=36-24393-ND|Name=Supplier Part Number 1|ReadOnlyState=3
|RECORD=34|OwnerIndex=855|IndexInSheet=-1|OwnerPartId=-1|Location.X=780|Location.X_Frac=54698|Location.Y=649|Location.Y_Frac=45302|Color=8388608|FontID=1|Text=J10|Name=Designator|ReadOnlyState=1
|RECORD=41|OwnerIndex=855|IndexInSheet=-1|OwnerPartId=-1|Location.X=780|Location.X_Frac=54698|Location.Y=620|Location.Y_Frac=54698|Color=8388608|FontID=1|Text=GNSS Standoff|Name=Comment
|RECORD=44|OwnerIndex=855
|RECORD=1|LibReference=GNSS Standoff|PartCount=2|DisplayModeCount=1|IndexInSheet=109|OwnerPartId=-1|Location.X=790|Location.Y=590|CurrentPartId=1|LibraryPath=*|SourceLibraryName=FPGA_CONN.SchLib|TargetFileName=*|AreaColor=11599871|Color=128|PartIDLocked=T|NotUseDBTableName=T|DesignItemId=GNSS Standoff
|RECORD=12|OwnerIndex=862|IsNotAccesible=T|OwnerPartId=1|Location.X=790|Location.Y=590|Radius=9|Radius_Frac=45302|LineWidth=1|EndAngle=360.000|Color=16711680
|RECORD=41|OwnerIndex=862|IndexInSheet=1|OwnerPartId=-1|Location.X=780|Location.X_Frac=54698|Location.Y=605|Color=8388608|FontID=1|IsHidden=T|Text=Digi-Key|Name=Supplier 1|ReadOnlyState=3
|RECORD=41|OwnerIndex=862|IndexInSheet=2|OwnerPartId=-1|Location.X=780|Location.X_Frac=54698|Location.Y=560|Location.Y_Frac=54698|Color=8388608|FontID=1|Text=36-24393-ND|Name=Supplier Part Number 1|ReadOnlyState=3
|RECORD=34|OwnerIndex=862|IndexInSheet=-1|OwnerPartId=-1|Location.X=780|Location.X_Frac=54698|Location.Y=599|Location.Y_Frac=45302|Color=8388608|FontID=1|Text=J11|Name=Designator|ReadOnlyState=1
|RECORD=41|OwnerIndex=862|IndexInSheet=-1|OwnerPartId=-1|Location.X=780|Location.X_Frac=54698|Location.Y=570|Location.Y_Frac=54698|Color=8388608|FontID=1|Text=GNSS Standoff|Name=Comment
|RECORD=44|OwnerIndex=862
|RECORD=1|LibReference=GNSS Standoff|PartCount=2|DisplayModeCount=1|IndexInSheet=110|OwnerPartId=-1|Location.X=790|Location.Y=540|CurrentPartId=1|LibraryPath=*|SourceLibraryName=FPGA_CONN.SchLib|TargetFileName=*|AreaColor=11599871|Color=128|PartIDLocked=T|NotUseDBTableName=T|DesignItemId=GNSS Standoff
|RECORD=12|OwnerIndex=869|IsNotAccesible=T|OwnerPartId=1|Location.X=790|Location.Y=540|Radius=9|Radius_Frac=45302|LineWidth=1|EndAngle=360.000|Color=16711680
|RECORD=41|OwnerIndex=869|IndexInSheet=1|OwnerPartId=-1|Location.X=780|Location.X_Frac=54698|Location.Y=555|Color=8388608|FontID=1|IsHidden=T|Text=Digi-Key|Name=Supplier 1|ReadOnlyState=3
|RECORD=41|OwnerIndex=869|IndexInSheet=2|OwnerPartId=-1|Location.X=780|Location.X_Frac=54698|Location.Y=510|Location.Y_Frac=54698|Color=8388608|FontID=1|Text=36-24393-ND|Name=Supplier Part Number 1|ReadOnlyState=3
|RECORD=34|OwnerIndex=869|IndexInSheet=-1|OwnerPartId=-1|Location.X=780|Location.X_Frac=54698|Location.Y=549|Location.Y_Frac=45302|Color=8388608|FontID=1|Text=J12|Name=Designator|ReadOnlyState=1
|RECORD=41|OwnerIndex=869|IndexInSheet=-1|OwnerPartId=-1|Location.X=780|Location.X_Frac=54698|Location.Y=520|Location.Y_Frac=54698|Color=8388608|FontID=1|Text=GNSS Standoff|Name=Comment
|RECORD=44|OwnerIndex=869
|RECORD=1|LibReference=GNSS Standoff|PartCount=2|DisplayModeCount=1|IndexInSheet=111|OwnerPartId=-1|Location.X=790|Location.Y=490|CurrentPartId=1|LibraryPath=*|SourceLibraryName=FPGA_CONN.SchLib|TargetFileName=*|AreaColor=11599871|Color=128|PartIDLocked=T|NotUseDBTableName=T|DesignItemId=GNSS Standoff
|RECORD=12|OwnerIndex=876|IsNotAccesible=T|OwnerPartId=1|Location.X=790|Location.Y=490|Radius=9|Radius_Frac=45302|LineWidth=1|EndAngle=360.000|Color=16711680
|RECORD=41|OwnerIndex=876|IndexInSheet=1|OwnerPartId=-1|Location.X=780|Location.X_Frac=54698|Location.Y=505|Color=8388608|FontID=1|IsHidden=T|Text=Digi-Key|Name=Supplier 1|ReadOnlyState=3
|RECORD=41|OwnerIndex=876|IndexInSheet=2|OwnerPartId=-1|Location.X=780|Location.X_Frac=54698|Location.Y=460|Location.Y_Frac=54698|Color=8388608|FontID=1|Text=36-24393-ND|Name=Supplier Part Number 1|ReadOnlyState=3
|RECORD=34|OwnerIndex=876|IndexInSheet=-1|OwnerPartId=-1|Location.X=780|Location.X_Frac=54698|Location.Y=499|Location.Y_Frac=45302|Color=8388608|FontID=1|Text=J14|Name=Designator|ReadOnlyState=1
|RECORD=41|OwnerIndex=876|IndexInSheet=-1|OwnerPartId=-1|Location.X=780|Location.X_Frac=54698|Location.Y=470|Location.Y_Frac=54698|Color=8388608|FontID=1|Text=GNSS Standoff|Name=Comment
|RECORD=44|OwnerIndex=876
|RECORD=1|LibReference=M3 screw|PartCount=2|DisplayModeCount=1|IndexInSheet=112|OwnerPartId=-1|Location.X=1100|Location.Y=980|CurrentPartId=1|LibraryPath=*|SourceLibraryName=FPGA_CONN.SchLib|TargetFileName=*|AreaColor=11599871|Color=128|PartIDLocked=T|NotUseDBTableName=T|DesignItemId=M3 screw
|RECORD=12|OwnerIndex=883|IsNotAccesible=T|OwnerPartId=1|Location.X=1100|Location.Y=980|Radius=9|Radius_Frac=18136|LineWidth=1|EndAngle=360.000|Color=16711680
|RECORD=41|OwnerIndex=883|IndexInSheet=1|OwnerPartId=-1|Location.X=1090|Location.X_Frac=81864|Location.Y=995|Color=8388608|FontID=1|IsHidden=T|Text=Digi-Key|Name=Supplier 1|ReadOnlyState=3
|RECORD=41|OwnerIndex=883|IndexInSheet=2|OwnerPartId=-1|Location.X=1090|Location.X_Frac=81864|Location.Y=950|Location.Y_Frac=81864|Color=8388608|FontID=1|Text=335-1156-ND|Name=Supplier Part Number 1|ReadOnlyState=3
|RECORD=34|OwnerIndex=883|IndexInSheet=-1|OwnerPartId=-1|Location.X=1090|Location.X_Frac=81864|Location.Y=989|Location.Y_Frac=18136|Color=8388608|FontID=1|Text=J15|Name=Designator|ReadOnlyState=1
|RECORD=41|OwnerIndex=883|IndexInSheet=-1|OwnerPartId=-1|Location.X=1090|Location.X_Frac=81864|Location.Y=960|Location.Y_Frac=81864|Color=8388608|FontID=1|Text=M3 screw|Name=Comment
|RECORD=44|OwnerIndex=883
|RECORD=1|LibReference=M3 screw|PartCount=2|DisplayModeCount=1|IndexInSheet=113|OwnerPartId=-1|Location.X=1100|Location.Y=930|CurrentPartId=1|LibraryPath=*|SourceLibraryName=FPGA_CONN.SchLib|TargetFileName=*|AreaColor=11599871|Color=128|PartIDLocked=T|NotUseDBTableName=T|DesignItemId=M3 screw
|RECORD=12|OwnerIndex=890|IsNotAccesible=T|OwnerPartId=1|Location.X=1100|Location.Y=930|Radius=9|Radius_Frac=18136|LineWidth=1|EndAngle=360.000|Color=16711680
|RECORD=41|OwnerIndex=890|IndexInSheet=1|OwnerPartId=-1|Location.X=1090|Location.X_Frac=81864|Location.Y=945|Color=8388608|FontID=1|IsHidden=T|Text=Digi-Key|Name=Supplier 1|ReadOnlyState=3
|RECORD=41|OwnerIndex=890|IndexInSheet=2|OwnerPartId=-1|Location.X=1090|Location.X_Frac=81864|Location.Y=900|Location.Y_Frac=81864|Color=8388608|FontID=1|Text=335-1156-ND|Name=Supplier Part Number 1|ReadOnlyState=3
|RECORD=34|OwnerIndex=890|IndexInSheet=-1|OwnerPartId=-1|Location.X=1090|Location.X_Frac=81864|Location.Y=939|Location.Y_Frac=18136|Color=8388608|FontID=1|Text=J16|Name=Designator|ReadOnlyState=1
|RECORD=41|OwnerIndex=890|IndexInSheet=-1|OwnerPartId=-1|Location.X=1090|Location.X_Frac=81864|Location.Y=910|Location.Y_Frac=81864|Color=8388608|FontID=1|Text=M3 screw|Name=Comment
|RECORD=44|OwnerIndex=890
|RECORD=1|LibReference=M3 screw|PartCount=2|DisplayModeCount=1|IndexInSheet=114|OwnerPartId=-1|Location.X=1100|Location.Y=880|CurrentPartId=1|LibraryPath=*|SourceLibraryName=FPGA_CONN.SchLib|TargetFileName=*|AreaColor=11599871|Color=128|PartIDLocked=T|NotUseDBTableName=T|DesignItemId=M3 screw
|RECORD=12|OwnerIndex=897|IsNotAccesible=T|OwnerPartId=1|Location.X=1100|Location.Y=880|Radius=9|Radius_Frac=18136|LineWidth=1|EndAngle=360.000|Color=16711680
|RECORD=41|OwnerIndex=897|IndexInSheet=1|OwnerPartId=-1|Location.X=1090|Location.X_Frac=81864|Location.Y=895|Color=8388608|FontID=1|IsHidden=T|Text=Digi-Key|Name=Supplier 1|ReadOnlyState=3
|RECORD=41|OwnerIndex=897|IndexInSheet=2|OwnerPartId=-1|Location.X=1090|Location.X_Frac=81864|Location.Y=850|Location.Y_Frac=81864|Color=8388608|FontID=1|Text=335-1156-ND|Name=Supplier Part Number 1|ReadOnlyState=3
|RECORD=34|OwnerIndex=897|IndexInSheet=-1|OwnerPartId=-1|Location.X=1090|Location.X_Frac=81864|Location.Y=889|Location.Y_Frac=18136|Color=8388608|FontID=1|Text=J17|Name=Designator|ReadOnlyState=1
|RECORD=41|OwnerIndex=897|IndexInSheet=-1|OwnerPartId=-1|Location.X=1090|Location.X_Frac=81864|Location.Y=860|Location.Y_Frac=81864|Color=8388608|FontID=1|Text=M3 screw|Name=Comment
|RECORD=44|OwnerIndex=897
|RECORD=1|LibReference=M3 screw|PartCount=2|DisplayModeCount=1|IndexInSheet=115|OwnerPartId=-1|Location.X=1100|Location.Y=830|CurrentPartId=1|LibraryPath=*|SourceLibraryName=FPGA_CONN.SchLib|TargetFileName=*|AreaColor=11599871|Color=128|PartIDLocked=T|NotUseDBTableName=T|DesignItemId=M3 screw
|RECORD=12|OwnerIndex=904|IsNotAccesible=T|OwnerPartId=1|Location.X=1100|Location.Y=830|Radius=9|Radius_Frac=18136|LineWidth=1|EndAngle=360.000|Color=16711680
|RECORD=41|OwnerIndex=904|IndexInSheet=1|OwnerPartId=-1|Location.X=1090|Location.X_Frac=81864|Location.Y=845|Color=8388608|FontID=1|IsHidden=T|Text=Digi-Key|Name=Supplier 1|ReadOnlyState=3
|RECORD=41|OwnerIndex=904|IndexInSheet=2|OwnerPartId=-1|Location.X=1090|Location.X_Frac=81864|Location.Y=800|Location.Y_Frac=81864|Color=8388608|FontID=1|Text=335-1156-ND|Name=Supplier Part Number 1|ReadOnlyState=3
|RECORD=34|OwnerIndex=904|IndexInSheet=-1|OwnerPartId=-1|Location.X=1090|Location.X_Frac=81864|Location.Y=839|Location.Y_Frac=18136|Color=8388608|FontID=1|Text=J18|Name=Designator|ReadOnlyState=1
|RECORD=41|OwnerIndex=904|IndexInSheet=-1|OwnerPartId=-1|Location.X=1090|Location.X_Frac=81864|Location.Y=810|Location.Y_Frac=81864|Color=8388608|FontID=1|Text=M3 screw|Name=Comment
|RECORD=44|OwnerIndex=904
|RECORD=1|LibReference=M3 screw|PartCount=2|DisplayModeCount=1|IndexInSheet=116|OwnerPartId=-1|Location.X=870|Location.Y=640|CurrentPartId=1|LibraryPath=*|SourceLibraryName=FPGA_CONN.SchLib|TargetFileName=*|AreaColor=11599871|Color=128|PartIDLocked=T|NotUseDBTableName=T|DesignItemId=M3 screw
|RECORD=12|OwnerIndex=911|IsNotAccesible=T|OwnerPartId=1|Location.X=870|Location.Y=640|Radius=9|Radius_Frac=18136|LineWidth=1|EndAngle=360.000|Color=16711680
|RECORD=41|OwnerIndex=911|IndexInSheet=1|OwnerPartId=-1|Location.X=860|Location.X_Frac=81864|Location.Y=655|Color=8388608|FontID=1|IsHidden=T|Text=Digi-Key|Name=Supplier 1|ReadOnlyState=3
|RECORD=41|OwnerIndex=911|IndexInSheet=2|OwnerPartId=-1|Location.X=860|Location.X_Frac=81864|Location.Y=610|Location.Y_Frac=81864|Color=8388608|FontID=1|Text=335-1156-ND|Name=Supplier Part Number 1|ReadOnlyState=3
|RECORD=34|OwnerIndex=911|IndexInSheet=-1|OwnerPartId=-1|Location.X=860|Location.X_Frac=81864|Location.Y=649|Location.Y_Frac=18136|Color=8388608|FontID=1|Text=J19|Name=Designator|ReadOnlyState=1
|RECORD=41|OwnerIndex=911|IndexInSheet=-1|OwnerPartId=-1|Location.X=860|Location.X_Frac=81864|Location.Y=620|Location.Y_Frac=81864|Color=8388608|FontID=1|Text=M3 screw|Name=Comment
|RECORD=44|OwnerIndex=911
|RECORD=1|LibReference=M3 screw|PartCount=2|DisplayModeCount=1|IndexInSheet=117|OwnerPartId=-1|Location.X=870|Location.Y=590|CurrentPartId=1|LibraryPath=*|SourceLibraryName=FPGA_CONN.SchLib|TargetFileName=*|AreaColor=11599871|Color=128|PartIDLocked=T|NotUseDBTableName=T|DesignItemId=M3 screw
|RECORD=12|OwnerIndex=918|IsNotAccesible=T|OwnerPartId=1|Location.X=870|Location.Y=590|Radius=9|Radius_Frac=18136|LineWidth=1|EndAngle=360.000|Color=16711680
|RECORD=41|OwnerIndex=918|IndexInSheet=1|OwnerPartId=-1|Location.X=860|Location.X_Frac=81864|Location.Y=605|Color=8388608|FontID=1|IsHidden=T|Text=Digi-Key|Name=Supplier 1|ReadOnlyState=3
|RECORD=41|OwnerIndex=918|IndexInSheet=2|OwnerPartId=-1|Location.X=860|Location.X_Frac=81864|Location.Y=560|Location.Y_Frac=81864|Color=8388608|FontID=1|Text=335-1156-ND|Name=Supplier Part Number 1|ReadOnlyState=3
|RECORD=34|OwnerIndex=918|IndexInSheet=-1|OwnerPartId=-1|Location.X=860|Location.X_Frac=81864|Location.Y=599|Location.Y_Frac=18136|Color=8388608|FontID=1|Text=J20|Name=Designator|ReadOnlyState=1
|RECORD=41|OwnerIndex=918|IndexInSheet=-1|OwnerPartId=-1|Location.X=860|Location.X_Frac=81864|Location.Y=570|Location.Y_Frac=81864|Color=8388608|FontID=1|Text=M3 screw|Name=Comment
|RECORD=44|OwnerIndex=918
|RECORD=1|LibReference=M3 screw|PartCount=2|DisplayModeCount=1|IndexInSheet=118|OwnerPartId=-1|Location.X=870|Location.Y=540|CurrentPartId=1|LibraryPath=*|SourceLibraryName=FPGA_CONN.SchLib|TargetFileName=*|AreaColor=11599871|Color=128|PartIDLocked=T|NotUseDBTableName=T|DesignItemId=M3 screw
|RECORD=12|OwnerIndex=925|IsNotAccesible=T|OwnerPartId=1|Location.X=870|Location.Y=540|Radius=9|Radius_Frac=18136|LineWidth=1|EndAngle=360.000|Color=16711680
|RECORD=41|OwnerIndex=925|IndexInSheet=1|OwnerPartId=-1|Location.X=860|Location.X_Frac=81864|Location.Y=555|Color=8388608|FontID=1|IsHidden=T|Text=Digi-Key|Name=Supplier 1|ReadOnlyState=3
|RECORD=41|OwnerIndex=925|IndexInSheet=2|OwnerPartId=-1|Location.X=860|Location.X_Frac=81864|Location.Y=510|Location.Y_Frac=81864|Color=8388608|FontID=1|Text=335-1156-ND|Name=Supplier Part Number 1|ReadOnlyState=3
|RECORD=34|OwnerIndex=925|IndexInSheet=-1|OwnerPartId=-1|Location.X=860|Location.X_Frac=81864|Location.Y=549|Location.Y_Frac=18136|Color=8388608|FontID=1|Text=J21|Name=Designator|ReadOnlyState=1
|RECORD=41|OwnerIndex=925|IndexInSheet=-1|OwnerPartId=-1|Location.X=860|Location.X_Frac=81864|Location.Y=520|Location.Y_Frac=81864|Color=8388608|FontID=1|Text=M3 screw|Name=Comment
|RECORD=44|OwnerIndex=925
|RECORD=1|LibReference=M3 screw|PartCount=2|DisplayModeCount=1|IndexInSheet=119|OwnerPartId=-1|Location.X=870|Location.Y=490|CurrentPartId=1|LibraryPath=*|SourceLibraryName=FPGA_CONN.SchLib|TargetFileName=*|AreaColor=11599871|Color=128|PartIDLocked=T|NotUseDBTableName=T|DesignItemId=M3 screw
|RECORD=12|OwnerIndex=932|IsNotAccesible=T|OwnerPartId=1|Location.X=870|Location.Y=490|Radius=9|Radius_Frac=18136|LineWidth=1|EndAngle=360.000|Color=16711680
|RECORD=41|OwnerIndex=932|IndexInSheet=1|OwnerPartId=-1|Location.X=860|Location.X_Frac=81864|Location.Y=505|Color=8388608|FontID=1|IsHidden=T|Text=Digi-Key|Name=Supplier 1|ReadOnlyState=3
|RECORD=41|OwnerIndex=932|IndexInSheet=2|OwnerPartId=-1|Location.X=860|Location.X_Frac=81864|Location.Y=460|Location.Y_Frac=81864|Color=8388608|FontID=1|Text=335-1156-ND|Name=Supplier Part Number 1|ReadOnlyState=3
|RECORD=34|OwnerIndex=932|IndexInSheet=-1|OwnerPartId=-1|Location.X=860|Location.X_Frac=81864|Location.Y=499|Location.Y_Frac=18136|Color=8388608|FontID=1|Text=J22|Name=Designator|ReadOnlyState=1
|RECORD=41|OwnerIndex=932|IndexInSheet=-1|OwnerPartId=-1|Location.X=860|Location.X_Frac=81864|Location.Y=470|Location.Y_Frac=81864|Color=8388608|FontID=1|Text=M3 screw|Name=Comment
|RECORD=44|OwnerIndex=932
|RECORD=1|LibReference=M3 screw|PartCount=2|DisplayModeCount=1|IndexInSheet=120|OwnerPartId=-1|Location.X=1160|Location.Y=980|CurrentPartId=1|LibraryPath=*|SourceLibraryName=FPGA_CONN.SchLib|TargetFileName=*|AreaColor=11599871|Color=128|PartIDLocked=T|NotUseDBTableName=T|DesignItemId=M3 screw
|RECORD=12|OwnerIndex=939|IsNotAccesible=T|OwnerPartId=1|Location.X=1160|Location.Y=980|Radius=9|Radius_Frac=18136|LineWidth=1|EndAngle=360.000|Color=16711680
|RECORD=41|OwnerIndex=939|IndexInSheet=1|OwnerPartId=-1|Location.X=1150|Location.X_Frac=81864|Location.Y=995|Color=8388608|FontID=1|IsHidden=T|Text=Digi-Key|Name=Supplier 1|ReadOnlyState=3
|RECORD=41|OwnerIndex=939|IndexInSheet=2|OwnerPartId=-1|Location.X=1150|Location.X_Frac=81864|Location.Y=950|Location.Y_Frac=81864|Color=8388608|FontID=1|Text=335-1156-ND|Name=Supplier Part Number 1|ReadOnlyState=3
|RECORD=34|OwnerIndex=939|IndexInSheet=-1|OwnerPartId=-1|Location.X=1150|Location.X_Frac=81864|Location.Y=989|Location.Y_Frac=18136|Color=8388608|FontID=1|Text=J23|Name=Designator|ReadOnlyState=1
|RECORD=41|OwnerIndex=939|IndexInSheet=-1|OwnerPartId=-1|Location.X=1150|Location.X_Frac=81864|Location.Y=960|Location.Y_Frac=81864|Color=8388608|FontID=1|Text=M3 screw|Name=Comment
|RECORD=44|OwnerIndex=939
|RECORD=1|LibReference=M3 screw|PartCount=2|DisplayModeCount=1|IndexInSheet=121|OwnerPartId=-1|Location.X=1160|Location.Y=930|CurrentPartId=1|LibraryPath=*|SourceLibraryName=FPGA_CONN.SchLib|TargetFileName=*|AreaColor=11599871|Color=128|PartIDLocked=T|NotUseDBTableName=T|DesignItemId=M3 screw
|RECORD=12|OwnerIndex=946|IsNotAccesible=T|OwnerPartId=1|Location.X=1160|Location.Y=930|Radius=9|Radius_Frac=18136|LineWidth=1|EndAngle=360.000|Color=16711680
|RECORD=41|OwnerIndex=946|IndexInSheet=1|OwnerPartId=-1|Location.X=1150|Location.X_Frac=81864|Location.Y=945|Color=8388608|FontID=1|IsHidden=T|Text=Digi-Key|Name=Supplier 1|ReadOnlyState=3
|RECORD=41|OwnerIndex=946|IndexInSheet=2|OwnerPartId=-1|Location.X=1150|Location.X_Frac=81864|Location.Y=900|Location.Y_Frac=81864|Color=8388608|FontID=1|Text=335-1156-ND|Name=Supplier Part Number 1|ReadOnlyState=3
|RECORD=34|OwnerIndex=946|IndexInSheet=-1|OwnerPartId=-1|Location.X=1150|Location.X_Frac=81864|Location.Y=939|Location.Y_Frac=18136|Color=8388608|FontID=1|Text=J24|Name=Designator|ReadOnlyState=1
|RECORD=41|OwnerIndex=946|IndexInSheet=-1|OwnerPartId=-1|Location.X=1150|Location.X_Frac=81864|Location.Y=910|Location.Y_Frac=81864|Color=8388608|FontID=1|Text=M3 screw|Name=Comment
|RECORD=44|OwnerIndex=946
|RECORD=1|LibReference=M3 screw|PartCount=2|DisplayModeCount=1|IndexInSheet=122|OwnerPartId=-1|Location.X=1160|Location.Y=880|CurrentPartId=1|LibraryPath=*|SourceLibraryName=FPGA_CONN.SchLib|TargetFileName=*|AreaColor=11599871|Color=128|PartIDLocked=T|NotUseDBTableName=T|DesignItemId=M3 screw
|RECORD=12|OwnerIndex=953|IsNotAccesible=T|OwnerPartId=1|Location.X=1160|Location.Y=880|Radius=9|Radius_Frac=18136|LineWidth=1|EndAngle=360.000|Color=16711680
|RECORD=41|OwnerIndex=953|IndexInSheet=1|OwnerPartId=-1|Location.X=1150|Location.X_Frac=81864|Location.Y=895|Color=8388608|FontID=1|IsHidden=T|Text=Digi-Key|Name=Supplier 1|ReadOnlyState=3
|RECORD=41|OwnerIndex=953|IndexInSheet=2|OwnerPartId=-1|Location.X=1150|Location.X_Frac=81864|Location.Y=850|Location.Y_Frac=81864|Color=8388608|FontID=1|Text=335-1156-ND|Name=Supplier Part Number 1|ReadOnlyState=3
|RECORD=34|OwnerIndex=953|IndexInSheet=-1|OwnerPartId=-1|Location.X=1150|Location.X_Frac=81864|Location.Y=889|Location.Y_Frac=18136|Color=8388608|FontID=1|Text=J25|Name=Designator|ReadOnlyState=1
|RECORD=41|OwnerIndex=953|IndexInSheet=-1|OwnerPartId=-1|Location.X=1150|Location.X_Frac=81864|Location.Y=860|Location.Y_Frac=81864|Color=8388608|FontID=1|Text=M3 screw|Name=Comment
|RECORD=44|OwnerIndex=953
|RECORD=1|LibReference=M3 screw|PartCount=2|DisplayModeCount=1|IndexInSheet=123|OwnerPartId=-1|Location.X=1160|Location.Y=830|CurrentPartId=1|LibraryPath=*|SourceLibraryName=FPGA_CONN.SchLib|TargetFileName=*|AreaColor=11599871|Color=128|PartIDLocked=T|NotUseDBTableName=T|DesignItemId=M3 screw
|RECORD=12|OwnerIndex=960|IsNotAccesible=T|OwnerPartId=1|Location.X=1160|Location.Y=830|Radius=9|Radius_Frac=18136|LineWidth=1|EndAngle=360.000|Color=16711680
|RECORD=41|OwnerIndex=960|IndexInSheet=1|OwnerPartId=-1|Location.X=1150|Location.X_Frac=81864|Location.Y=845|Color=8388608|FontID=1|IsHidden=T|Text=Digi-Key|Name=Supplier 1|ReadOnlyState=3
|RECORD=41|OwnerIndex=960|IndexInSheet=2|OwnerPartId=-1|Location.X=1150|Location.X_Frac=81864|Location.Y=800|Location.Y_Frac=81864|Color=8388608|FontID=1|Text=335-1156-ND|Name=Supplier Part Number 1|ReadOnlyState=3
|RECORD=34|OwnerIndex=960|IndexInSheet=-1|OwnerPartId=-1|Location.X=1150|Location.X_Frac=81864|Location.Y=839|Location.Y_Frac=18136|Color=8388608|FontID=1|Text=J26|Name=Designator|ReadOnlyState=1
|RECORD=41|OwnerIndex=960|IndexInSheet=-1|OwnerPartId=-1|Location.X=1150|Location.X_Frac=81864|Location.Y=810|Location.Y_Frac=81864|Color=8388608|FontID=1|Text=M3 screw|Name=Comment
|RECORD=44|OwnerIndex=960
|RECORD=1|LibReference=M3 screw|PartCount=2|DisplayModeCount=1|IndexInSheet=124|OwnerPartId=-1|Location.X=940|Location.Y=640|CurrentPartId=1|LibraryPath=*|SourceLibraryName=FPGA_CONN.SchLib|TargetFileName=*|AreaColor=11599871|Color=128|PartIDLocked=T|NotUseDBTableName=T|DesignItemId=M3 screw
|RECORD=12|OwnerIndex=967|IsNotAccesible=T|OwnerPartId=1|Location.X=940|Location.Y=640|Radius=9|Radius_Frac=18136|LineWidth=1|EndAngle=360.000|Color=16711680
|RECORD=41|OwnerIndex=967|IndexInSheet=1|OwnerPartId=-1|Location.X=930|Location.X_Frac=81864|Location.Y=655|Color=8388608|FontID=1|IsHidden=T|Text=Digi-Key|Name=Supplier 1|ReadOnlyState=3
|RECORD=41|OwnerIndex=967|IndexInSheet=2|OwnerPartId=-1|Location.X=930|Location.X_Frac=81864|Location.Y=610|Location.Y_Frac=81864|Color=8388608|FontID=1|Text=335-1156-ND|Name=Supplier Part Number 1|ReadOnlyState=3
|RECORD=34|OwnerIndex=967|IndexInSheet=-1|OwnerPartId=-1|Location.X=930|Location.X_Frac=81864|Location.Y=649|Location.Y_Frac=18136|Color=8388608|FontID=1|Text=J27|Name=Designator|ReadOnlyState=1
|RECORD=41|OwnerIndex=967|IndexInSheet=-1|OwnerPartId=-1|Location.X=930|Location.X_Frac=81864|Location.Y=620|Location.Y_Frac=81864|Color=8388608|FontID=1|Text=M3 screw|Name=Comment
|RECORD=44|OwnerIndex=967
|RECORD=1|LibReference=M3 screw|PartCount=2|DisplayModeCount=1|IndexInSheet=125|OwnerPartId=-1|Location.X=940|Location.Y=590|CurrentPartId=1|LibraryPath=*|SourceLibraryName=FPGA_CONN.SchLib|TargetFileName=*|AreaColor=11599871|Color=128|PartIDLocked=T|NotUseDBTableName=T|DesignItemId=M3 screw
|RECORD=12|OwnerIndex=974|IsNotAccesible=T|OwnerPartId=1|Location.X=940|Location.Y=590|Radius=9|Radius_Frac=18136|LineWidth=1|EndAngle=360.000|Color=16711680
|RECORD=41|OwnerIndex=974|IndexInSheet=1|OwnerPartId=-1|Location.X=930|Location.X_Frac=81864|Location.Y=605|Color=8388608|FontID=1|IsHidden=T|Text=Digi-Key|Name=Supplier 1|ReadOnlyState=3
|RECORD=41|OwnerIndex=974|IndexInSheet=2|OwnerPartId=-1|Location.X=930|Location.X_Frac=81864|Location.Y=560|Location.Y_Frac=81864|Color=8388608|FontID=1|Text=335-1156-ND|Name=Supplier Part Number 1|ReadOnlyState=3
|RECORD=34|OwnerIndex=974|IndexInSheet=-1|OwnerPartId=-1|Location.X=930|Location.X_Frac=81864|Location.Y=599|Location.Y_Frac=18136|Color=8388608|FontID=1|Text=J28|Name=Designator|ReadOnlyState=1
|RECORD=41|OwnerIndex=974|IndexInSheet=-1|OwnerPartId=-1|Location.X=930|Location.X_Frac=81864|Location.Y=570|Location.Y_Frac=81864|Color=8388608|FontID=1|Text=M3 screw|Name=Comment
|RECORD=44|OwnerIndex=974
|RECORD=1|LibReference=M3 screw|PartCount=2|DisplayModeCount=1|IndexInSheet=126|OwnerPartId=-1|Location.X=940|Location.Y=540|CurrentPartId=1|LibraryPath=*|SourceLibraryName=FPGA_CONN.SchLib|TargetFileName=*|AreaColor=11599871|Color=128|PartIDLocked=T|NotUseDBTableName=T|DesignItemId=M3 screw
|RECORD=12|OwnerIndex=981|IsNotAccesible=T|OwnerPartId=1|Location.X=940|Location.Y=540|Radius=9|Radius_Frac=18136|LineWidth=1|EndAngle=360.000|Color=16711680
|RECORD=41|OwnerIndex=981|IndexInSheet=1|OwnerPartId=-1|Location.X=930|Location.X_Frac=81864|Location.Y=555|Color=8388608|FontID=1|IsHidden=T|Text=Digi-Key|Name=Supplier 1|ReadOnlyState=3
|RECORD=41|OwnerIndex=981|IndexInSheet=2|OwnerPartId=-1|Location.X=930|Location.X_Frac=81864|Location.Y=510|Location.Y_Frac=81864|Color=8388608|FontID=1|Text=335-1156-ND|Name=Supplier Part Number 1|ReadOnlyState=3
|RECORD=34|OwnerIndex=981|IndexInSheet=-1|OwnerPartId=-1|Location.X=930|Location.X_Frac=81864|Location.Y=549|Location.Y_Frac=18136|Color=8388608|FontID=1|Text=J29|Name=Designator|ReadOnlyState=1
|RECORD=41|OwnerIndex=981|IndexInSheet=-1|OwnerPartId=-1|Location.X=930|Location.X_Frac=81864|Location.Y=520|Location.Y_Frac=81864|Color=8388608|FontID=1|Text=M3 screw|Name=Comment
|RECORD=44|OwnerIndex=981
|RECORD=1|LibReference=M3 screw|PartCount=2|DisplayModeCount=1|IndexInSheet=127|OwnerPartId=-1|Location.X=940|Location.Y=490|CurrentPartId=1|LibraryPath=*|SourceLibraryName=FPGA_CONN.SchLib|TargetFileName=*|AreaColor=11599871|Color=128|PartIDLocked=T|NotUseDBTableName=T|DesignItemId=M3 screw
|RECORD=12|OwnerIndex=988|IsNotAccesible=T|OwnerPartId=1|Location.X=940|Location.Y=490|Radius=9|Radius_Frac=18136|LineWidth=1|EndAngle=360.000|Color=16711680
|RECORD=41|OwnerIndex=988|IndexInSheet=1|OwnerPartId=-1|Location.X=930|Location.X_Frac=81864|Location.Y=505|Color=8388608|FontID=1|IsHidden=T|Text=Digi-Key|Name=Supplier 1|ReadOnlyState=3
|RECORD=41|OwnerIndex=988|IndexInSheet=2|OwnerPartId=-1|Location.X=930|Location.X_Frac=81864|Location.Y=460|Location.Y_Frac=81864|Color=8388608|FontID=1|Text=335-1156-ND|Name=Supplier Part Number 1|ReadOnlyState=3
|RECORD=34|OwnerIndex=988|IndexInSheet=-1|OwnerPartId=-1|Location.X=930|Location.X_Frac=81864|Location.Y=499|Location.Y_Frac=18136|Color=8388608|FontID=1|Text=J30|Name=Designator|ReadOnlyState=1
|RECORD=41|OwnerIndex=988|IndexInSheet=-1|OwnerPartId=-1|Location.X=930|Location.X_Frac=81864|Location.Y=470|Location.Y_Frac=81864|Color=8388608|FontID=1|Text=M3 screw|Name=Comment
|RECORD=44|OwnerIndex=988
|RECORD=1|LibReference=M3 screw|PartCount=2|DisplayModeCount=1|IndexInSheet=128|OwnerPartId=-1|Location.X=1270|Location.Y=990|CurrentPartId=1|LibraryPath=*|SourceLibraryName=FPGA_CONN.SchLib|TargetFileName=*|AreaColor=11599871|Color=128|PartIDLocked=T|NotUseDBTableName=T|DesignItemId=M3 screw
|RECORD=12|OwnerIndex=995|IsNotAccesible=T|OwnerPartId=1|Location.X=1270|Location.Y=990|Radius=9|Radius_Frac=18136|LineWidth=1|EndAngle=360.000|Color=16711680
|RECORD=41|OwnerIndex=995|IndexInSheet=1|OwnerPartId=-1|Location.X=1260|Location.X_Frac=81864|Location.Y=1005|Color=8388608|FontID=1|IsHidden=T|Text=Digi-Key|Name=Supplier 1|ReadOnlyState=3
|RECORD=41|OwnerIndex=995|IndexInSheet=2|OwnerPartId=-1|Location.X=1260|Location.X_Frac=81864|Location.Y=960|Location.Y_Frac=81864|Color=8388608|FontID=1|Text=335-1156-ND|Name=Supplier Part Number 1|ReadOnlyState=3
|RECORD=34|OwnerIndex=995|IndexInSheet=-1|OwnerPartId=-1|Location.X=1260|Location.X_Frac=81864|Location.Y=999|Location.Y_Frac=18136|Color=8388608|FontID=1|Text=J32|Name=Designator|ReadOnlyState=1
|RECORD=41|OwnerIndex=995|IndexInSheet=-1|OwnerPartId=-1|Location.X=1260|Location.X_Frac=81864|Location.Y=970|Location.Y_Frac=81864|Color=8388608|FontID=1|Text=M3 screw|Name=Comment
|RECORD=44|OwnerIndex=995
|RECORD=1|LibReference=M3 screw|PartCount=2|DisplayModeCount=1|IndexInSheet=129|OwnerPartId=-1|Location.X=1330|Location.Y=990|CurrentPartId=1|LibraryPath=*|SourceLibraryName=FPGA_CONN.SchLib|TargetFileName=*|AreaColor=11599871|Color=128|PartIDLocked=T|NotUseDBTableName=T|DesignItemId=M3 screw
|RECORD=12|OwnerIndex=1002|IsNotAccesible=T|OwnerPartId=1|Location.X=1330|Location.Y=990|Radius=9|Radius_Frac=18136|LineWidth=1|EndAngle=360.000|Color=16711680
|RECORD=41|OwnerIndex=1002|IndexInSheet=1|OwnerPartId=-1|Location.X=1320|Location.X_Frac=81864|Location.Y=1005|Color=8388608|FontID=1|IsHidden=T|Text=Digi-Key|Name=Supplier 1|ReadOnlyState=3
|RECORD=41|OwnerIndex=1002|IndexInSheet=2|OwnerPartId=-1|Location.X=1320|Location.X_Frac=81864|Location.Y=960|Location.Y_Frac=81864|Color=8388608|FontID=1|Text=335-1156-ND|Name=Supplier Part Number 1|ReadOnlyState=3
|RECORD=34|OwnerIndex=1002|IndexInSheet=-1|OwnerPartId=-1|Location.X=1320|Location.X_Frac=81864|Location.Y=999|Location.Y_Frac=18136|Color=8388608|FontID=1|Text=J33|Name=Designator|ReadOnlyState=1
|RECORD=41|OwnerIndex=1002|IndexInSheet=-1|OwnerPartId=-1|Location.X=1320|Location.X_Frac=81864|Location.Y=970|Location.Y_Frac=81864|Color=8388608|FontID=1|Text=M3 screw|Name=Comment
|RECORD=44|OwnerIndex=1002
|RECORD=4|IndexInSheet=130|OwnerPartId=-1|Location.X=1260|Location.Y=1020|Color=8388608|FontID=1|Text=PCIe Bracket screws
|RECORD=1|LibReference=SMTC-TSW-105-05-X-S|ComponentDescription=0.025" SQ Post Header, Through-hole, Vertical, -55 to 125 degC, 2.54 mm Pitch, 5-Pin, Male, RoHS|PartCount=2|DisplayModeCount=1|IndexInSheet=131|OwnerPartId=-1|Location.X=410|Location.Y=100|Orientation=1|CurrentPartId=1|LibraryPath=*|SourceLibraryName=Altium Content Vault|TargetFileName=*|AreaColor=11599871|Color=128|PartIDLocked=T|DesignItemId=CMP-1024-00366-1|AllPinCount=5
|RECORD=2|OwnerIndex=1010|OwnerPartId=1|FormalType=1|Electrical=4|PinConglomerate=48|PinLength=20|Location.X=430|Location.Y=150|Name=1|Designator=1|PinPropagationDelay=0.000000E+000
|RECORD=2|OwnerIndex=1010|OwnerPartId=1|FormalType=1|Electrical=4|PinConglomerate=48|PinLength=20|Location.X=430|Location.Y=140|Name=2|Designator=2|PinPropagationDelay=0.000000E+000
|RECORD=2|OwnerIndex=1010|OwnerPartId=1|FormalType=1|Electrical=4|PinConglomerate=48|PinLength=20|Location.X=430|Location.Y=130|Name=3|Designator=3|PinPropagationDelay=0.000000E+000
|RECORD=2|OwnerIndex=1010|OwnerPartId=1|FormalType=1|Electrical=4|PinConglomerate=48|PinLength=20|Location.X=430|Location.Y=120|Name=4|Designator=4|PinPropagationDelay=0.000000E+000
|RECORD=2|OwnerIndex=1010|OwnerPartId=1|FormalType=1|Electrical=4|PinConglomerate=48|PinLength=20|Location.X=430|Location.Y=110|Name=5|Designator=5|PinPropagationDelay=0.000000E+000
|RECORD=6|OwnerIndex=1010|IsNotAccesible=T|IndexInSheet=5|OwnerPartId=1|LineWidth=1|Color=16711680|LocationCount=2|X1=430|Y1=150|X2=423|Y2=150
|RECORD=8|OwnerIndex=1010|IsNotAccesible=T|IndexInSheet=6|OwnerPartId=1|Location.X=420|Location.Y=150|Radius=3|SecondaryRadius=3|LineWidth=1|Color=16711680|AreaColor=16711680|IsSolid=T
|RECORD=6|OwnerIndex=1010|IsNotAccesible=T|IndexInSheet=7|OwnerPartId=1|LineWidth=1|Color=16711680|LocationCount=5|X1=430|Y1=100|X2=410|Y2=100|X3=410|Y3=160|X4=430|Y4=160|X5=430|Y5=100
|RECORD=6|OwnerIndex=1010|IsNotAccesible=T|IndexInSheet=8|OwnerPartId=1|LineWidth=1|Color=16711680|LocationCount=2|X1=430|Y1=140|X2=423|Y2=140
|RECORD=8|OwnerIndex=1010|IsNotAccesible=T|IndexInSheet=9|OwnerPartId=1|Location.X=420|Location.Y=140|Radius=3|SecondaryRadius=3|LineWidth=1|Color=16711680|AreaColor=16711680|IsSolid=T
|RECORD=6|OwnerIndex=1010|IsNotAccesible=T|IndexInSheet=10|OwnerPartId=1|LineWidth=1|Color=16711680|LocationCount=2|X1=430|Y1=130|X2=423|Y2=130
|RECORD=6|OwnerIndex=1010|IsNotAccesible=T|IndexInSheet=11|OwnerPartId=1|LineWidth=1|Color=16711680|LocationCount=2|X1=430|Y1=120|X2=423|Y2=120
|RECORD=8|OwnerIndex=1010|IsNotAccesible=T|IndexInSheet=12|OwnerPartId=1|Location.X=420|Location.Y=130|Radius=3|SecondaryRadius=3|LineWidth=1|Color=16711680|AreaColor=16711680|IsSolid=T
|RECORD=8|OwnerIndex=1010|IsNotAccesible=T|IndexInSheet=13|OwnerPartId=1|Location.X=420|Location.Y=120|Radius=3|SecondaryRadius=3|LineWidth=1|Color=16711680|AreaColor=16711680|IsSolid=T
|RECORD=6|OwnerIndex=1010|IsNotAccesible=T|IndexInSheet=14|OwnerPartId=1|LineWidth=1|Color=16711680|LocationCount=2|X1=430|Y1=110|X2=423|Y2=110
|RECORD=8|OwnerIndex=1010|IsNotAccesible=T|IndexInSheet=15|OwnerPartId=1|Location.X=420|Location.Y=110|Radius=3|SecondaryRadius=3|LineWidth=1|Color=16711680|AreaColor=16711680|IsSolid=T
|RECORD=41|OwnerIndex=1010|IndexInSheet=16|OwnerPartId=-1|Location.X=409|Location.Y=161|Color=8388608|FontID=1|IsHidden=T|Text=DM, 8/1988|Name=PackageVersion
|RECORD=41|OwnerIndex=1010|IndexInSheet=17|OwnerPartId=-1|Location.X=409|Location.Y=161|Color=8388608|FontID=1|IsHidden=T|Text=TSW-105-05-L-S|Name=PartNumber
|RECORD=41|OwnerIndex=1010|IndexInSheet=18|OwnerPartId=-1|Location.X=409|Location.Y=161|Color=8388608|FontID=1|IsHidden=T|Text=Vertical|Name=Orientation
|RECORD=41|OwnerIndex=1010|IndexInSheet=19|OwnerPartId=-1|Location.X=409|Location.Y=161|Color=8388608|FontID=1|IsHidden=T|Text=-55 to 125 degC|Name=Temperature Range
|RECORD=41|OwnerIndex=1010|IndexInSheet=20|OwnerPartId=-1|Location.X=409|Location.Y=161|Color=8388608|FontID=1|IsHidden=T|Text=Manufacturer URL|Name=ComponentLink1Description
|RECORD=41|OwnerIndex=1010|IndexInSheet=21|OwnerPartId=-1|Location.X=409|Location.Y=161|Color=8388608|FontID=1|IsHidden=T|Text=.025[0.64] SQ. Post Terminal Strip Assembly|Name=PackageDescription
|RECORD=41|OwnerIndex=1010|IndexInSheet=22|OwnerPartId=-1|Location.X=409|Location.Y=161|Color=8388608|FontID=1|IsHidden=T|Text=2.54 mm|Name=Pitch
|RECORD=41|OwnerIndex=1010|IndexInSheet=23|OwnerPartId=-1|Location.X=409|Location.Y=161|Color=8388608|FontID=3|IsHidden=T|Text=http://www.samtec.com/documents/webfiles/pdf/TSW_TH.PDF|Name=ComponentLink2URL
|RECORD=41|OwnerIndex=1010|IndexInSheet=24|OwnerPartId=-1|Location.X=409|Location.Y=161|Color=8388608|FontID=1|IsHidden=T|Text=TSW-105-05-X-S|Name=PackageReference
|RECORD=41|OwnerIndex=1010|IndexInSheet=25|OwnerPartId=-1|Location.X=409|Location.Y=161|Color=8388608|FontID=1|IsHidden=T|Text=Datasheet|Name=ComponentLink2Description
|RECORD=41|OwnerIndex=1010|IndexInSheet=26|OwnerPartId=-1|Location.X=409|Location.Y=161|Color=8388608|FontID=1|IsHidden=T|Text=Through-hole|Name=Mounting Technology
|RECORD=41|OwnerIndex=1010|IndexInSheet=27|OwnerPartId=-1|Location.X=409|Location.Y=161|Color=8388608|FontID=1|IsHidden=T|Text=F-214|Name=DatasheetVersion
|RECORD=41|OwnerIndex=1010|IndexInSheet=28|OwnerPartId=-1|Location.X=409|Location.Y=161|Color=8388608|FontID=3|IsHidden=T|Text=http://www.samtec.com|Name=ComponentLink1URL
|RECORD=41|OwnerIndex=1010|IndexInSheet=29|OwnerPartId=-1|Location.X=409|Location.Y=161|Color=8388608|FontID=1|IsHidden=T|Text=True|Name=RoHS
|RECORD=41|OwnerIndex=1010|IndexInSheet=30|OwnerPartId=-1|Location.X=409|Location.Y=161|Color=8388608|FontID=3|IsHidden=T|Text=http://www.samtec.com/documents/webfiles/cpdf/TSW-XXX-XX-XXX-X-XX-XXX-MKT.pdf|Name=ComponentLink3URL
|RECORD=41|OwnerIndex=1010|IndexInSheet=31|OwnerPartId=-1|Location.X=409|Location.Y=161|Color=8388608|FontID=1|IsHidden=T|Text=Package Specification|Name=ComponentLink3Description
|RECORD=41|OwnerIndex=1010|IndexInSheet=32|OwnerPartId=-1|Location.X=409|Location.Y=161|Color=8388608|FontID=1|IsHidden=T|Text=Samtec|Name=Manufacturer
|RECORD=34|OwnerIndex=1010|IndexInSheet=-1|OwnerPartId=-1|Location.X=409|Location.Y=161|Color=8388608|FontID=1|Text=P1|Name=Designator|ReadOnlyState=1
|RECORD=41|OwnerIndex=1010|IndexInSheet=-1|OwnerPartId=-1|Location.X=409|Location.Y=89|Color=8388608|FontID=1|Text=TSW-105-05-L-S|Name=Comment
|RECORD=44|OwnerIndex=1010
|RECORD=45|OwnerIndex=1051|IndexInSheet=-1|Description=.025 SQ Post Terminal Strip Assembly, 1x5 Pins, Vertical, 2.54mm Pitch, Male|UseComponentLibrary=T|ModelName=SMTC-TSW-105-05-X-S|ModelType=PCBLIB|DatafileCount=1|ModelDatafileEntity0=SMTC-TSW-105-05-X-S|ModelDatafileKind0=PCBLib|IsCurrent=T|DatalinksLocked=T|DatabaseDatalinksLocked=T
|RECORD=46|OwnerIndex=1052
|RECORD=48|OwnerIndex=1052
|RECORD=41|OwnerIndex=1054|IndexInSheet=-1|OwnerPartId=-1|Color=8388608|FontID=1|IsHidden=T|Text=2D|Name=Available Preview Images
|RECORD=17|IndexInSheet=132|OwnerPartId=-1|ShowNetName=T|Location.X=530|Location.Y=180|Orientation=1|Color=128|FontID=1|Text=+3.3V
|RECORD=17|IndexInSheet=133|OwnerPartId=-1|Style=4|ShowNetName=T|Location.X=500|Location.Y=70|Orientation=3|Color=128|FontID=1|Text=GND
|RECORD=17|IndexInSheet=134|OwnerPartId=-1|ShowNetName=T|Location.X=520|Location.Y=130|Color=255|FontID=1|Text=ANADC_I2C_SCL|IsCrossSheetConnector=T
|RECORD=17|IndexInSheet=135|OwnerPartId=-1|ShowNetName=T|Location.X=520|Location.Y=120|Color=255|FontID=1|Text=ANADC_I2C_SDA|IsCrossSheetConnector=T
|RECORD=17|IndexInSheet=136|OwnerPartId=-1|Style=1|ShowNetName=T|Location.X=680|Location.Y=100|Color=255|FontID=1|Text=MAC_FREQ_CTRL|IsCrossSheetConnector=T
|RECORD=1|LibReference=RES-2|ComponentDescription=Chip Resistor, 0 Ohm, 0.1 W, -55 to 155 degC, 0402 (1005 Metric), RoHS, Tape and Reel|PartCount=2|DisplayModeCount=1|IndexInSheet=137|OwnerPartId=-1|Location.X=560|Location.Y=100|CurrentPartId=1|LibraryPath=*|SourceLibraryName=Altium Content Vault|TargetFileName=*|AreaColor=11599871|Color=128|PartIDLocked=T|DesignItemId=CMP-2000-07451-1|AllPinCount=2|ComponentKindVersion2=5
|RECORD=2|OwnerIndex=1061|OwnerPartId=1|FormalType=1|Electrical=4|PinConglomerate=32|PinLength=10|Location.X=580|Location.Y=100|Name=2|Designator=2|PinPropagationDelay=0.000000E+000
|RECORD=2|OwnerIndex=1061|OwnerPartId=1|FormalType=1|Electrical=4|PinConglomerate=34|PinLength=10|Location.X=560|Location.Y=100|Name=1|Designator=1|PinPropagationDelay=0.000000E+000
|RECORD=6|OwnerIndex=1061|IsNotAccesible=T|IndexInSheet=2|OwnerPartId=1|LineWidth=1|Color=16711680|LocationCount=10|X1=580|Y1=100|X2=576|Y2=100|X3=575|Y3=98|X4=573|Y4=102|X5=571|Y5=98|X6=569|Y6=102|X7=567|Y7=98|X8=565|Y8=102|X9=564|Y9=100|X10=560|Y10=100
|RECORD=41|OwnerIndex=1061|IndexInSheet=3|OwnerPartId=-1|Location.X=548|Location.Y=115|Color=8388608|FontID=1|IsHidden=T|Text=50V|Name=Voltage Rating (DC)
|RECORD=41|OwnerIndex=1061|IndexInSheet=4|OwnerPartId=-1|Location.X=548|Location.Y=115|Color=8388608|FontID=1|IsHidden=T|Text=2|Name=Number of Terminations
|RECORD=41|OwnerIndex=1061|IndexInSheet=5|OwnerPartId=-1|Location.X=548|Location.Y=115|Color=8388608|FontID=1|IsHidden=T|Text=SurfaceMount|Name=Mount
|RECORD=41|OwnerIndex=1061|IndexInSheet=6|OwnerPartId=-1|Location.X=548|Location.Y=115|Color=8388608|FontID=1|IsHidden=T|Text=0.35mm|Name=Height
|RECORD=41|OwnerIndex=1061|IndexInSheet=7|OwnerPartId=-1|Location.X=548|Location.Y=115|Color=8388608|FontID=1|IsHidden=T|Text=TapeandReel|Name=Packaging
|RECORD=41|OwnerIndex=1061|IndexInSheet=8|OwnerPartId=-1|Location.X=548|Location.Y=115|Color=8388608|FontID=1|IsHidden=T|Text=Tin|Name=Contact Plating
|RECORD=41|OwnerIndex=1061|IndexInSheet=9|OwnerPartId=-1|Location.X=548|Location.Y=115|Color=8388608|FontID=3|IsHidden=T|Text=http://www.panasonic.com/|Name=Manufacturer URL
|RECORD=41|OwnerIndex=1061|IndexInSheet=10|OwnerPartId=-1|Location.X=548|Location.Y=115|Color=8388608|FontID=1|IsHidden=T|Text=ThickFilm|Name=Composition
|RECORD=41|OwnerIndex=1061|IndexInSheet=11|OwnerPartId=-1|Location.X=548|Location.Y=115|Color=8388608|FontID=1|IsHidden=T|Text=155degC|Name=Max Operating Temperature
|RECORD=41|OwnerIndex=1061|IndexInSheet=12|OwnerPartId=-1|Location.X=548|Location.Y=115|Color=8388608|FontID=1|IsHidden=T|Text=600ppm/??C|Name=Temperature Coefficient
|RECORD=41|OwnerIndex=1061|IndexInSheet=13|OwnerPartId=-1|Location.X=548|Location.Y=115|Color=8388608|FontID=1|IsHidden=T|Text=NoSVHC|Name=REACH SVHC
|RECORD=41|OwnerIndex=1061|IndexInSheet=14|OwnerPartId=-1|Location.X=548|Location.Y=115|Color=8388608|FontID=1|IsHidden=T|Text=0402|Name=Case/Package
|RECORD=41|OwnerIndex=1061|IndexInSheet=15|OwnerPartId=-1|Location.X=548|Location.Y=115|Color=8388608|FontID=1|IsHidden=T|Text=100mW|Name=Max Power Dissipation
|RECORD=41|OwnerIndex=1061|IndexInSheet=16|OwnerPartId=-1|Location.X=548|Location.Y=115|Color=8388608|FontID=1|IsHidden=T|Text=402|Name=Package Reference
|RECORD=41|OwnerIndex=1061|IndexInSheet=17|OwnerPartId=-1|Location.X=548|Location.Y=115|Color=8388608|FontID=1|IsHidden=T|Text=0.5mm|Name=Depth
|RECORD=41|OwnerIndex=1061|IndexInSheet=18|OwnerPartId=-1|Location.X=548|Location.Y=115|Color=8388608|FontID=1|IsHidden=T|Text=Panasonic|Name=Manufacturer
|RECORD=41|OwnerIndex=1061|IndexInSheet=19|OwnerPartId=-1|Location.X=548|Location.Y=115|Color=8388608|FontID=1|IsHidden=T|Text=2-Pin Surface Mount Device, Body 1 x 0.5 mm|Name=Package Description
|RECORD=41|OwnerIndex=1061|IndexInSheet=20|OwnerPartId=-1|Location.X=548|Location.Y=115|Color=8388608|FontID=3|IsHidden=T|Text=https://industrial.panasonic.com/cdbs/www-data/pdf/RDA0000/AOA0000C301.pdf|Name=Datasheet URL
|RECORD=41|OwnerIndex=1061|IndexInSheet=21|OwnerPartId=-1|Location.X=548|Location.Y=115|Color=8388608|FontID=1|IsHidden=T|Text=True|Name=RoHSCompliant
|RECORD=41|OwnerIndex=1061|IndexInSheet=22|OwnerPartId=-1|Location.X=548|Location.Y=115|Color=8388608|FontID=1|IsHidden=T|Text=0402|Name=Case Code (Imperial)
|RECORD=41|OwnerIndex=1061|IndexInSheet=23|OwnerPartId=-1|Location.X=548|Location.Y=115|Color=8388608|FontID=1|IsHidden=T|Text=0mOhm|Name=Resistance
|RECORD=41|OwnerIndex=1061|IndexInSheet=24|OwnerPartId=-1|Location.X=548|Location.Y=115|Color=8388608|FontID=1|IsHidden=T|Text=Not|Name=Military Standard
|RECORD=41|OwnerIndex=1061|IndexInSheet=25|OwnerPartId=-1|Location.X=548|Location.Y=115|Color=8388608|FontID=1|IsHidden=T|Text=5%|Name=Tolerance
|RECORD=41|OwnerIndex=1061|IndexInSheet=26|OwnerPartId=-1|Location.X=548|Location.Y=115|Color=8388608|FontID=1|IsHidden=T|Text=-55degC|Name=Min Operating Temperature
|RECORD=41|OwnerIndex=1061|IndexInSheet=27|OwnerPartId=-1|Location.X=548|Location.Y=115|Color=8388608|FontID=1|IsHidden=T|Text=100mW|Name=Power Rating
|RECORD=41|OwnerIndex=1061|IndexInSheet=28|OwnerPartId=-1|Location.X=548|Location.Y=115|Color=8388608|FontID=1|IsHidden=T|Text=03/2015|Name=Datasheet Version
|RECORD=41|OwnerIndex=1061|IndexInSheet=29|OwnerPartId=-1|Location.X=548|Location.Y=115|Color=8388608|FontID=1|IsHidden=T|Text=1mm|Name=Length
|RECORD=41|OwnerIndex=1061|IndexInSheet=30|OwnerPartId=-1|Location.X=548|Location.Y=115|Color=8388608|FontID=1|IsHidden=T|Text=1005|Name=Case Code (Metric)
|RECORD=41|OwnerIndex=1061|IndexInSheet=31|OwnerPartId=-1|Location.X=548|Location.Y=115|Color=8388608|FontID=1|IsHidden=T|Text=SMD/SMT|Name=Termination
|RECORD=41|OwnerIndex=1061|IndexInSheet=32|OwnerPartId=-1|Location.X=548|Location.Y=115|Color=8388608|FontID=1|IsHidden=T|Text=SurfaceMount|Name=Mounting Technology
|RECORD=41|OwnerIndex=1061|IndexInSheet=33|OwnerPartId=-1|Location.X=548|Location.Y=115|Color=8388608|FontID=1|IsHidden=T|Text=50V|Name=Voltage Rating
|RECORD=41|OwnerIndex=1061|IndexInSheet=34|OwnerPartId=-1|Location.X=548|Location.Y=115|Color=8388608|FontID=1|IsHidden=T|Text=0.02inch|Name=Width
|RECORD=41|OwnerIndex=1061|IndexInSheet=35|OwnerPartId=-1|Location.X=548|Location.Y=115|Color=8388608|FontID=1|IsHidden=T|Text=1|Name=Package Quantity
|RECORD=41|OwnerIndex=1061|IndexInSheet=36|OwnerPartId=-1|Location.X=548|Location.Y=115|Color=8388608|FontID=1|IsHidden=T|Text=LeadFree|Name=Lead Free
|RECORD=41|OwnerIndex=1061|IndexInSheet=37|OwnerPartId=-1|Location.X=548|Location.Y=115|Color=8388608|FontID=1|IsHidden=T|Text=No|Name=Radiation Hardening
|RECORD=34|OwnerIndex=1061|IndexInSheet=-1|OwnerPartId=-1|Location.X=540|Location.Y=100|Color=8388608|FontID=1|Text=R48|Name=Designator|ReadOnlyState=1
|RECORD=41|OwnerIndex=1061|IndexInSheet=-1|OwnerPartId=-1|Location.X=580|Location.Y=100|Color=8388608|FontID=1|Text=DNI_0_1%_0402|Name=Comment
|RECORD=44|OwnerIndex=1061
|RECORD=45|OwnerIndex=1104|IndexInSheet=-1|Description=Chip Resistor, 2-Leads, Body 1.05x0.55mm, IPC High Density|UseComponentLibrary=T|ModelName=RESC1005X40X25LL05T05|ModelType=PCBLIB|DatafileCount=1|ModelDatafileEntity0=RESC1005X40X25LL05T05|ModelDatafileKind0=PCBLib|IsCurrent=T|DatalinksLocked=T|DatabaseDatalinksLocked=T
|RECORD=46|OwnerIndex=1105
|RECORD=48|OwnerIndex=1105
|RECORD=41|OwnerIndex=1107|IndexInSheet=-1|OwnerPartId=-1|Color=8388608|FontID=1|IsHidden=T|Text=2D|Name=Available Preview Images
|RECORD=45|OwnerIndex=1104|IndexInSheet=-1|Description=Chip Resistor, 2-Leads, Body 1.05x0.55mm, IPC Low Density|UseComponentLibrary=T|ModelName=RESC1005X40X25ML05T05|ModelType=PCBLIB|DatafileCount=1|ModelDatafileEntity0=RESC1005X40X25ML05T05|ModelDatafileKind0=PCBLib|DatalinksLocked=T|DatabaseDatalinksLocked=T
|RECORD=46|OwnerIndex=1109
|RECORD=48|OwnerIndex=1109
|RECORD=41|OwnerIndex=1111|IndexInSheet=-1|OwnerPartId=-1|Color=8388608|FontID=1|IsHidden=T|Text=2D|Name=Available Preview Images
|RECORD=45|OwnerIndex=1104|IndexInSheet=-1|Description=Chip Resistor, 2-Leads, Body 1.05x0.55mm, IPC Medium Density|UseComponentLibrary=T|ModelName=RESC1005X40X25NL05T05|ModelType=PCBLIB|DatafileCount=1|ModelDatafileEntity0=RESC1005X40X25NL05T05|ModelDatafileKind0=PCBLib|DatalinksLocked=T|DatabaseDatalinksLocked=T
|RECORD=46|OwnerIndex=1113
|RECORD=48|OwnerIndex=1113
|RECORD=41|OwnerIndex=1115|IndexInSheet=-1|OwnerPartId=-1|Color=8388608|FontID=1|IsHidden=T|Text=2D|Name=Available Preview Images
|RECORD=4|IndexInSheet=138|OwnerPartId=-1|Location.X=540|Location.Y=50|Color=8388608|FontID=1|Text=Allow DAC daughter card to control atomic clock analog input
|RECORD=1|LibReference=GNSS Header 16-pin|PartCount=2|DisplayModeCount=1|IndexInSheet=139|OwnerPartId=-1|Location.X=580|Location.Y=950|CurrentPartId=1|LibraryPath=*|SourceLibraryName=FPGA_CONN.SchLib|TargetFileName=*|AreaColor=11599871|Color=128|PartIDLocked=T|DesignItemId=GNSS Header 16-pin|AllPinCount=16
|RECORD=41|OwnerIndex=1118|OwnerPartId=-1|Location.X=548|Location.Y=1040|Color=8388608|FontID=1|IsHidden=T|Text=Digi-Key|Name=Supplier 1|ReadOnlyState=3
|RECORD=14|OwnerIndex=1118|IsNotAccesible=T|IndexInSheet=1|OwnerPartId=1|Location.X=580|Location.Y=940|Corner.X=630|Corner.Y=1040|Color=128|AreaColor=11599871|IsSolid=T
|RECORD=2|OwnerIndex=1118|OwnerPartId=1|FormalType=1|Electrical=4|PinConglomerate=58|PinLength=30|Location.X=580|Location.Y=1030|Name=1|Designator=1|SwapIDPart=Ž&Ž||PinPropagationDelay=0.000000E+000
|RECORD=2|OwnerIndex=1118|OwnerPartId=1|FormalType=1|Electrical=4|PinConglomerate=58|PinLength=30|Location.X=580|Location.Y=1020|Name=2|Designator=2|SwapIDPart=Ž&Ž||PinPropagationDelay=0.000000E+000
|RECORD=2|OwnerIndex=1118|OwnerPartId=1|FormalType=1|Electrical=4|PinConglomerate=58|PinLength=30|Location.X=580|Location.Y=1010|Name=3|Designator=3|SwapIDPart=Ž&Ž||PinPropagationDelay=0.000000E+000
|RECORD=2|OwnerIndex=1118|OwnerPartId=1|FormalType=1|Electrical=4|PinConglomerate=58|PinLength=30|Location.X=580|Location.Y=1000|Name=4|Designator=4|SwapIDPart=Ž&Ž||PinPropagationDelay=0.000000E+000
|RECORD=2|OwnerIndex=1118|OwnerPartId=1|FormalType=1|Electrical=4|PinConglomerate=56|PinLength=30|Location.X=630|Location.Y=1030|Name=5|Designator=5|SwapIDPart=Ž&Ž||PinPropagationDelay=0.000000E+000
|RECORD=2|OwnerIndex=1118|OwnerPartId=1|FormalType=1|Electrical=4|PinConglomerate=56|PinLength=30|Location.X=630|Location.Y=1020|Name=6|Designator=6|SwapIDPart=Ž&Ž||PinPropagationDelay=0.000000E+000
|RECORD=2|OwnerIndex=1118|OwnerPartId=1|FormalType=1|Electrical=4|PinConglomerate=56|PinLength=30|Location.X=630|Location.Y=1010|Name=7|Designator=7|SwapIDPart=Ž&Ž||PinPropagationDelay=0.000000E+000
|RECORD=2|OwnerIndex=1118|OwnerPartId=1|FormalType=1|Electrical=4|PinConglomerate=56|PinLength=30|Location.X=630|Location.Y=1000|Name=8|Designator=8|SwapIDPart=Ž&Ž||PinPropagationDelay=0.000000E+000
|RECORD=2|OwnerIndex=1118|OwnerPartId=1|FormalType=1|Electrical=4|PinConglomerate=58|PinLength=30|Location.X=580|Location.Y=980|Name=9|Designator=9|SwapIDPart=Ž&Ž||PinPropagationDelay=0.000000E+000
|RECORD=2|OwnerIndex=1118|OwnerPartId=1|FormalType=1|Electrical=4|PinConglomerate=58|PinLength=30|Location.X=580|Location.Y=970|Name=10|Designator=10|SwapIDPart=Ž&Ž||PinPropagationDelay=0.000000E+000
|RECORD=2|OwnerIndex=1118|OwnerPartId=1|FormalType=1|Electrical=4|PinConglomerate=58|PinLength=30|Location.X=580|Location.Y=960|Name=11|Designator=11|SwapIDPart=Ž&Ž||PinPropagationDelay=0.000000E+000
|RECORD=2|OwnerIndex=1118|OwnerPartId=1|FormalType=1|Electrical=4|PinConglomerate=58|PinLength=30|Location.X=580|Location.Y=950|Name=12|Designator=12|SwapIDPart=Ž&Ž||PinPropagationDelay=0.000000E+000
|RECORD=2|OwnerIndex=1118|OwnerPartId=1|FormalType=1|Electrical=4|PinConglomerate=56|PinLength=30|Location.X=630|Location.Y=980|Name=13|Designator=13|SwapIDPart=Ž&Ž||PinPropagationDelay=0.000000E+000
|RECORD=2|OwnerIndex=1118|OwnerPartId=1|FormalType=1|Electrical=4|PinConglomerate=56|PinLength=30|Location.X=630|Location.Y=970|Name=14|Designator=14|SwapIDPart=Ž&Ž||PinPropagationDelay=0.000000E+000
|RECORD=2|OwnerIndex=1118|OwnerPartId=1|FormalType=1|Electrical=4|PinConglomerate=56|PinLength=30|Location.X=630|Location.Y=960|Name=15|Designator=15|SwapIDPart=Ž&Ž||PinPropagationDelay=0.000000E+000
|RECORD=2|OwnerIndex=1118|OwnerPartId=1|FormalType=1|Electrical=4|PinConglomerate=56|PinLength=30|Location.X=630|Location.Y=950|Name=16|Designator=16|SwapIDPart=Ž&Ž||PinPropagationDelay=0.000000E+000
|RECORD=41|OwnerIndex=1118|IndexInSheet=18|OwnerPartId=-1|Location.X=580|Location.Y=920|Color=8388608|FontID=1|Text=SAM11878-ND|Name=Supplier Part Number 1|ReadOnlyState=3
|RECORD=34|OwnerIndex=1118|IndexInSheet=-1|OwnerPartId=-1|Location.X=580|Location.Y=1040|Color=8388608|FontID=1|Text=J6|Name=Designator|ReadOnlyState=1
|RECORD=41|OwnerIndex=1118|IndexInSheet=-1|OwnerPartId=-1|Location.X=580|Location.Y=930|Color=8388608|FontID=1|Text=GNSS Header 16-pin|Name=Comment
|RECORD=44|OwnerIndex=1118
|RECORD=45|OwnerIndex=1156|IndexInSheet=-1|ModelName=GNSS Header 16-pin|ModelType=PCBLIB|DatafileCount=1|ModelDatafileEntity0=GNSS Header 16-pin|ModelDatafileKind0=PCBLib|IsCurrent=T
|RECORD=46|OwnerIndex=1157
|RECORD=48|OwnerIndex=1157
|RECORD=1|LibReference=GNSS Header 16-pin|PartCount=2|DisplayModeCount=1|IndexInSheet=140|OwnerPartId=-1|Location.X=470|Location.Y=440|CurrentPartId=1|LibraryPath=*|SourceLibraryName=FPGA_CONN.SchLib|TargetFileName=*|AreaColor=11599871|Color=128|PartIDLocked=T|DesignItemId=GNSS Header 16-pin|AllPinCount=16
|RECORD=41|OwnerIndex=1160|OwnerPartId=-1|Location.X=438|Location.Y=530|Color=8388608|FontID=1|IsHidden=T|Text=Digi-Key|Name=Supplier 1|ReadOnlyState=3
|RECORD=14|OwnerIndex=1160|IsNotAccesible=T|IndexInSheet=1|OwnerPartId=1|Location.X=470|Location.Y=430|Corner.X=520|Corner.Y=530|Color=128|AreaColor=11599871|IsSolid=T
|RECORD=2|OwnerIndex=1160|OwnerPartId=1|FormalType=1|Electrical=4|PinConglomerate=58|PinLength=30|Location.X=470|Location.Y=520|Name=1|Designator=1|SwapIDPart=Ž&Ž||PinPropagationDelay=0.000000E+000
|RECORD=2|OwnerIndex=1160|OwnerPartId=1|FormalType=1|Electrical=4|PinConglomerate=58|PinLength=30|Location.X=470|Location.Y=510|Name=2|Designator=2|SwapIDPart=Ž&Ž||PinPropagationDelay=0.000000E+000
|RECORD=2|OwnerIndex=1160|OwnerPartId=1|FormalType=1|Electrical=4|PinConglomerate=58|PinLength=30|Location.X=470|Location.Y=500|Name=3|Designator=3|SwapIDPart=Ž&Ž||PinPropagationDelay=0.000000E+000
|RECORD=2|OwnerIndex=1160|OwnerPartId=1|FormalType=1|Electrical=4|PinConglomerate=58|PinLength=30|Location.X=470|Location.Y=490|Name=4|Designator=4|SwapIDPart=Ž&Ž||PinPropagationDelay=0.000000E+000
|RECORD=2|OwnerIndex=1160|OwnerPartId=1|FormalType=1|Electrical=4|PinConglomerate=56|PinLength=30|Location.X=520|Location.Y=520|Name=5|Designator=5|SwapIDPart=Ž&Ž||PinPropagationDelay=0.000000E+000
|RECORD=2|OwnerIndex=1160|OwnerPartId=1|FormalType=1|Electrical=4|PinConglomerate=56|PinLength=30|Location.X=520|Location.Y=510|Name=6|Designator=6|SwapIDPart=Ž&Ž||PinPropagationDelay=0.000000E+000
|RECORD=2|OwnerIndex=1160|OwnerPartId=1|FormalType=1|Electrical=4|PinConglomerate=56|PinLength=30|Location.X=520|Location.Y=500|Name=7|Designator=7|SwapIDPart=Ž&Ž||PinPropagationDelay=0.000000E+000
|RECORD=2|OwnerIndex=1160|OwnerPartId=1|FormalType=1|Electrical=4|PinConglomerate=56|PinLength=30|Location.X=520|Location.Y=490|Name=8|Designator=8|SwapIDPart=Ž&Ž||PinPropagationDelay=0.000000E+000
|RECORD=2|OwnerIndex=1160|OwnerPartId=1|FormalType=1|Electrical=4|PinConglomerate=58|PinLength=30|Location.X=470|Location.Y=470|Name=9|Designator=9|SwapIDPart=Ž&Ž||PinPropagationDelay=0.000000E+000
|RECORD=2|OwnerIndex=1160|OwnerPartId=1|FormalType=1|Electrical=4|PinConglomerate=58|PinLength=30|Location.X=470|Location.Y=460|Name=10|Designator=10|SwapIDPart=Ž&Ž||PinPropagationDelay=0.000000E+000
|RECORD=2|OwnerIndex=1160|OwnerPartId=1|FormalType=1|Electrical=4|PinConglomerate=58|PinLength=30|Location.X=470|Location.Y=450|Name=11|Designator=11|SwapIDPart=Ž&Ž||PinPropagationDelay=0.000000E+000
|RECORD=2|OwnerIndex=1160|OwnerPartId=1|FormalType=1|Electrical=4|PinConglomerate=58|PinLength=30|Location.X=470|Location.Y=440|Name=12|Designator=12|SwapIDPart=Ž&Ž||PinPropagationDelay=0.000000E+000
|RECORD=2|OwnerIndex=1160|OwnerPartId=1|FormalType=1|Electrical=4|PinConglomerate=56|PinLength=30|Location.X=520|Location.Y=470|Name=13|Designator=13|SwapIDPart=Ž&Ž||PinPropagationDelay=0.000000E+000
|RECORD=2|OwnerIndex=1160|OwnerPartId=1|FormalType=1|Electrical=4|PinConglomerate=56|PinLength=30|Location.X=520|Location.Y=460|Name=14|Designator=14|SwapIDPart=Ž&Ž||PinPropagationDelay=0.000000E+000
|RECORD=2|OwnerIndex=1160|OwnerPartId=1|FormalType=1|Electrical=4|PinConglomerate=56|PinLength=30|Location.X=520|Location.Y=450|Name=15|Designator=15|SwapIDPart=Ž&Ž||PinPropagationDelay=0.000000E+000
|RECORD=2|OwnerIndex=1160|OwnerPartId=1|FormalType=1|Electrical=4|PinConglomerate=56|PinLength=30|Location.X=520|Location.Y=440|Name=16|Designator=16|SwapIDPart=Ž&Ž||PinPropagationDelay=0.000000E+000
|RECORD=41|OwnerIndex=1160|IndexInSheet=18|OwnerPartId=-1|Location.X=470|Location.Y=410|Color=8388608|FontID=1|Text=SAM11878-ND|Name=Supplier Part Number 1|ReadOnlyState=3
|RECORD=34|OwnerIndex=1160|IndexInSheet=-1|OwnerPartId=-1|Location.X=470|Location.Y=530|Color=8388608|FontID=1|Text=J13|Name=Designator|ReadOnlyState=1
|RECORD=41|OwnerIndex=1160|IndexInSheet=-1|OwnerPartId=-1|Location.X=470|Location.Y=420|Color=8388608|FontID=1|Text=GNSS Header 16-pin|Name=Comment
|RECORD=44|OwnerIndex=1160
|RECORD=45|OwnerIndex=1198|IndexInSheet=-1|ModelName=GNSS Header 16-pin|ModelType=PCBLIB|DatafileCount=1|ModelDatafileEntity0=GNSS Header 16-pin|ModelDatafileKind0=PCBLib|IsCurrent=T
|RECORD=46|OwnerIndex=1199
|RECORD=48|OwnerIndex=1199
|RECORD=17|IndexInSheet=141|OwnerPartId=-1|Style=4|ShowNetName=T|Location.X=100|Location.Y=410|Orientation=3|Color=128|FontID=1|Text=GND
|RECORD=17|IndexInSheet=142|OwnerPartId=-1|Style=4|ShowNetName=T|Location.X=200|Location.Y=410|Orientation=3|Color=128|FontID=1|Text=GND
|RECORD=1|LibReference=CAP|ComponentDescription=C0603X104K5RACAUTO|PartCount=2|DisplayModeCount=2|IndexInSheet=143|OwnerPartId=-1|Location.X=140|Location.Y=430|Orientation=1|CurrentPartId=1|SourceLibraryName=Altium Content Vault|TargetFileName=*|AreaColor=11599871|Color=128|PartIDLocked=F|DesignItemId=CMP-2006-00003-1|AllPinCount=2
|RECORD=2|OwnerIndex=1204|OwnerPartId=1|OwnerPartDisplayMode=1|FormalType=1|Electrical=4|PinConglomerate=35|PinLength=10|Location.X=150|Location.Y=430|Name=1|Designator=1|PinPropagationDelay=0.000000E+000
|RECORD=2|OwnerIndex=1204|OwnerPartId=1|OwnerPartDisplayMode=1|FormalType=1|Electrical=4|PinConglomerate=33|PinLength=10|Location.X=150|Location.Y=440|Name=2|Designator=2|PinPropagationDelay=0.000000E+000
|RECORD=13|OwnerIndex=1204|IsNotAccesible=T|IndexInSheet=2|OwnerPartId=1|OwnerPartDisplayMode=1|Location.X=158|Location.Y=430|Corner.X=142|Corner.Y=430|LineWidth=1|Color=16711680
|RECORD=13|OwnerIndex=1204|IsNotAccesible=T|IndexInSheet=3|OwnerPartId=1|OwnerPartDisplayMode=1|Location.X=150|Location.Y=434|Corner.X=150|Corner.Y=440|LineWidth=1|Color=16711680
|RECORD=12|OwnerIndex=1204|IsNotAccesible=T|IndexInSheet=4|OwnerPartId=1|OwnerPartDisplayMode=1|Location.X=150|Location.Y=450|Radius=16|LineWidth=1|StartAngle=241.000|EndAngle=270.000|Color=16711680
|RECORD=12|OwnerIndex=1204|IsNotAccesible=T|IndexInSheet=5|OwnerPartId=1|OwnerPartDisplayMode=1|Location.X=150|Location.Y=450|Radius=16|LineWidth=1|StartAngle=270.000|EndAngle=299.000|Color=16711680
|RECORD=2|OwnerIndex=1204|OwnerPartId=1|FormalType=1|Electrical=4|PinConglomerate=35|PinLength=10|Location.X=150|Location.Y=430|Name=1|Designator=1|PinPropagationDelay=0.000000E+000
|RECORD=2|OwnerIndex=1204|OwnerPartId=1|FormalType=1|Electrical=4|PinConglomerate=33|PinLength=10|Location.X=150|Location.Y=440|Name=2|Designator=2|PinPropagationDelay=0.000000E+000
|RECORD=13|OwnerIndex=1204|IsNotAccesible=T|IndexInSheet=8|OwnerPartId=1|Location.X=142|Location.Y=437|Corner.X=158|Corner.Y=437|LineWidth=1|Color=16711680
|RECORD=13|OwnerIndex=1204|IsNotAccesible=T|IndexInSheet=9|OwnerPartId=1|Location.X=158|Location.Y=433|Corner.X=142|Corner.Y=433|LineWidth=1|Color=16711680
|RECORD=6|OwnerIndex=1204|IsNotAccesible=T|IndexInSheet=10|OwnerPartId=1|LineWidth=1|Color=16711680|LocationCount=2|X1=150|Y1=430|X2=150|Y2=433
|RECORD=6|OwnerIndex=1204|IsNotAccesible=T|IndexInSheet=11|OwnerPartId=1|LineWidth=1|Color=16711680|LocationCount=2|X1=150|Y1=440|X2=150|Y2=437
|RECORD=41|OwnerIndex=1204|IndexInSheet=12|OwnerPartId=-1|Location.X=141|Location.Y=452|Color=8388608|FontID=1|IsHidden=T|Text=Kemet|Name=Manufacturer
|RECORD=41|OwnerIndex=1204|IndexInSheet=13|OwnerPartId=-1|Location.X=141|Location.Y=452|Color=8388608|FontID=1|IsHidden=T|Text=C0603X104K5RACAUTO|Name=Part Number
|RECORD=34|OwnerIndex=1204|IndexInSheet=-1|OwnerPartId=-1|Location.X=159|Location.Y=431|Color=8388608|FontID=1|Text=C57|Name=Designator|ReadOnlyState=1
|RECORD=41|OwnerIndex=1204|IndexInSheet=-1|OwnerPartId=-1|Location.X=159|Location.Y=421|Color=8388608|FontID=1|Text=0.1uF|Name=Comment
|RECORD=44|OwnerIndex=1204
|RECORD=45|OwnerIndex=1225|IndexInSheet=-1|Description=Chip Capacitor, 2-Leads, Body 1.60x0.80mm, IPC Low Density|UseComponentLibrary=T|ModelName=CAPC1608X87X45ML20T05|ModelType=PCBLIB|DatafileCount=1|ModelDatafileEntity0=CAPC1608X87X45ML20T05|ModelDatafileKind0=PCBLib|IsCurrent=T|DatalinksLocked=T|DatabaseDatalinksLocked=T
|RECORD=46|OwnerIndex=1226
|RECORD=48|OwnerIndex=1226
|RECORD=41|OwnerIndex=1228|IndexInSheet=-1|OwnerPartId=-1|Color=8388608|FontID=1|Text=2D|Name=Available Preview Images
|RECORD=45|OwnerIndex=1225|IndexInSheet=-1|Description=Chip Capacitor, 2-Leads, Body 1.60x0.80mm, IPC High Density|UseComponentLibrary=T|ModelName=CAPC1608X87X45LL20T05|ModelType=PCBLIB|DatafileCount=1|ModelDatafileEntity0=CAPC1608X87X45LL20T05|ModelDatafileKind0=PCBLib|DatalinksLocked=T|DatabaseDatalinksLocked=T
|RECORD=46|OwnerIndex=1230
|RECORD=48|OwnerIndex=1230
|RECORD=41|OwnerIndex=1232|IndexInSheet=-1|OwnerPartId=-1|Color=8388608|FontID=1|Text=2D|Name=Available Preview Images
|RECORD=45|OwnerIndex=1225|IndexInSheet=-1|Description=Chip Capacitor, 2-Leads, Body 1.60x0.80mm, IPC Medium Density|UseComponentLibrary=T|ModelName=CAPC1608X87X45NL20T05|ModelType=PCBLIB|DatafileCount=1|ModelDatafileEntity0=CAPC1608X87X45NL20T05|ModelDatafileKind0=PCBLib|DatalinksLocked=T|DatabaseDatalinksLocked=T
|RECORD=46|OwnerIndex=1234
|RECORD=48|OwnerIndex=1234
|RECORD=41|OwnerIndex=1236|IndexInSheet=-1|OwnerPartId=-1|Color=8388608|FontID=1|Text=2D|Name=Available Preview Images
|RECORD=1|LibReference=CAP|ComponentDescription=C0603X104K5RACAUTO|PartCount=2|DisplayModeCount=2|IndexInSheet=144|OwnerPartId=-1|Location.X=240|Location.Y=430|Orientation=1|CurrentPartId=1|SourceLibraryName=Altium Content Vault|TargetFileName=*|AreaColor=11599871|Color=128|PartIDLocked=F|DesignItemId=CMP-2006-00003-1|AllPinCount=2
|RECORD=2|OwnerIndex=1238|OwnerPartId=1|OwnerPartDisplayMode=1|FormalType=1|Electrical=4|PinConglomerate=35|PinLength=10|Location.X=250|Location.Y=430|Name=1|Designator=1|PinPropagationDelay=0.000000E+000
|RECORD=2|OwnerIndex=1238|OwnerPartId=1|OwnerPartDisplayMode=1|FormalType=1|Electrical=4|PinConglomerate=33|PinLength=10|Location.X=250|Location.Y=440|Name=2|Designator=2|PinPropagationDelay=0.000000E+000
|RECORD=13|OwnerIndex=1238|IsNotAccesible=T|IndexInSheet=2|OwnerPartId=1|OwnerPartDisplayMode=1|Location.X=258|Location.Y=430|Corner.X=242|Corner.Y=430|LineWidth=1|Color=16711680
|RECORD=13|OwnerIndex=1238|IsNotAccesible=T|IndexInSheet=3|OwnerPartId=1|OwnerPartDisplayMode=1|Location.X=250|Location.Y=434|Corner.X=250|Corner.Y=440|LineWidth=1|Color=16711680
|RECORD=12|OwnerIndex=1238|IsNotAccesible=T|IndexInSheet=4|OwnerPartId=1|OwnerPartDisplayMode=1|Location.X=250|Location.Y=450|Radius=16|LineWidth=1|StartAngle=241.000|EndAngle=270.000|Color=16711680
|RECORD=12|OwnerIndex=1238|IsNotAccesible=T|IndexInSheet=5|OwnerPartId=1|OwnerPartDisplayMode=1|Location.X=250|Location.Y=450|Radius=16|LineWidth=1|StartAngle=270.000|EndAngle=299.000|Color=16711680
|RECORD=2|OwnerIndex=1238|OwnerPartId=1|FormalType=1|Electrical=4|PinConglomerate=35|PinLength=10|Location.X=250|Location.Y=430|Name=1|Designator=1|PinPropagationDelay=0.000000E+000
|RECORD=2|OwnerIndex=1238|OwnerPartId=1|FormalType=1|Electrical=4|PinConglomerate=33|PinLength=10|Location.X=250|Location.Y=440|Name=2|Designator=2|PinPropagationDelay=0.000000E+000
|RECORD=13|OwnerIndex=1238|IsNotAccesible=T|IndexInSheet=8|OwnerPartId=1|Location.X=242|Location.Y=437|Corner.X=258|Corner.Y=437|LineWidth=1|Color=16711680
|RECORD=13|OwnerIndex=1238|IsNotAccesible=T|IndexInSheet=9|OwnerPartId=1|Location.X=258|Location.Y=433|Corner.X=242|Corner.Y=433|LineWidth=1|Color=16711680
|RECORD=6|OwnerIndex=1238|IsNotAccesible=T|IndexInSheet=10|OwnerPartId=1|LineWidth=1|Color=16711680|LocationCount=2|X1=250|Y1=430|X2=250|Y2=433
|RECORD=6|OwnerIndex=1238|IsNotAccesible=T|IndexInSheet=11|OwnerPartId=1|LineWidth=1|Color=16711680|LocationCount=2|X1=250|Y1=440|X2=250|Y2=437
|RECORD=41|OwnerIndex=1238|IndexInSheet=12|OwnerPartId=-1|Location.X=241|Location.Y=452|Color=8388608|FontID=1|IsHidden=T|Text=Kemet|Name=Manufacturer
|RECORD=41|OwnerIndex=1238|IndexInSheet=13|OwnerPartId=-1|Location.X=241|Location.Y=452|Color=8388608|FontID=1|IsHidden=T|Text=C0603X104K5RACAUTO|Name=Part Number
|RECORD=34|OwnerIndex=1238|IndexInSheet=-1|OwnerPartId=-1|Location.X=259|Location.Y=431|Color=8388608|FontID=1|Text=C64|Name=Designator|ReadOnlyState=1
|RECORD=41|OwnerIndex=1238|IndexInSheet=-1|OwnerPartId=-1|Location.X=259|Location.Y=421|Color=8388608|FontID=1|Text=0.1uF|Name=Comment
|RECORD=44|OwnerIndex=1238
|RECORD=45|OwnerIndex=1259|IndexInSheet=-1|Description=Chip Capacitor, 2-Leads, Body 1.60x0.80mm, IPC Low Density|UseComponentLibrary=T|ModelName=CAPC1608X87X45ML20T05|ModelType=PCBLIB|DatafileCount=1|ModelDatafileEntity0=CAPC1608X87X45ML20T05|ModelDatafileKind0=PCBLib|IsCurrent=T|DatalinksLocked=T|DatabaseDatalinksLocked=T
|RECORD=46|OwnerIndex=1260
|RECORD=48|OwnerIndex=1260
|RECORD=41|OwnerIndex=1262|IndexInSheet=-1|OwnerPartId=-1|Color=8388608|FontID=1|Text=2D|Name=Available Preview Images
|RECORD=45|OwnerIndex=1259|IndexInSheet=-1|Description=Chip Capacitor, 2-Leads, Body 1.60x0.80mm, IPC High Density|UseComponentLibrary=T|ModelName=CAPC1608X87X45LL20T05|ModelType=PCBLIB|DatafileCount=1|ModelDatafileEntity0=CAPC1608X87X45LL20T05|ModelDatafileKind0=PCBLib|DatalinksLocked=T|DatabaseDatalinksLocked=T
|RECORD=46|OwnerIndex=1264
|RECORD=48|OwnerIndex=1264
|RECORD=41|OwnerIndex=1266|IndexInSheet=-1|OwnerPartId=-1|Color=8388608|FontID=1|Text=2D|Name=Available Preview Images
|RECORD=45|OwnerIndex=1259|IndexInSheet=-1|Description=Chip Capacitor, 2-Leads, Body 1.60x0.80mm, IPC Medium Density|UseComponentLibrary=T|ModelName=CAPC1608X87X45NL20T05|ModelType=PCBLIB|DatafileCount=1|ModelDatafileEntity0=CAPC1608X87X45NL20T05|ModelDatafileKind0=PCBLib|DatalinksLocked=T|DatabaseDatalinksLocked=T
|RECORD=46|OwnerIndex=1268
|RECORD=48|OwnerIndex=1268
|RECORD=41|OwnerIndex=1270|IndexInSheet=-1|OwnerPartId=-1|Color=8388608|FontID=1|Text=2D|Name=Available Preview Images
|RECORD=1|LibReference=b4654b650e69147ec39a6b967a45e02|ComponentDescription=None|PartCount=2|DisplayModeCount=1|IndexInSheet=145|OwnerPartId=-1|Location.X=100|Location.Y=450|CurrentPartId=1|LibraryPath=*|SourceLibraryName=Altium Content Vault|TargetFileName=*|AreaColor=11599871|Color=128|PartIDLocked=T|DesignItemId=CMP-14477-000079-2|AllPinCount=2
|RECORD=2|OwnerIndex=1272|OwnerPartId=1|Electrical=4|PinConglomerate=49|PinLength=7|Location.X=100|Location.Y=443|Name=1|Designator=1|PinPropagationDelay=0.000000E+000
|RECORD=2|OwnerIndex=1272|OwnerPartId=1|Electrical=4|PinConglomerate=51|PinLength=6|Location.X=100|Location.Y=436|Name=2|Designator=2|PinPropagationDelay=0.000000E+000
|RECORD=13|OwnerIndex=1272|IsNotAccesible=T|IndexInSheet=2|OwnerPartId=1|Location.X=110|Location.Y=443|Corner.X=90|Corner.Y=443|LineWidth=1|Color=16711680
|RECORD=13|OwnerIndex=1272|IsNotAccesible=T|IndexInSheet=3|OwnerPartId=1|Location.X=110|Location.Y=437|Corner.X=90|Corner.Y=437|LineWidth=1|Color=16711680
|RECORD=13|OwnerIndex=1272|IsNotAccesible=T|IndexInSheet=4|OwnerPartId=1|Location.X=100|Location.Y=443|Corner.X=100|Corner.Y=446|LineWidth=1|Color=16711680
|RECORD=13|OwnerIndex=1272|IsNotAccesible=T|IndexInSheet=5|OwnerPartId=1|Location.X=100|Location.Y=436|Corner.X=100|Corner.Y=435|LineWidth=1|Color=16711680
|RECORD=41|OwnerIndex=1272|IndexInSheet=6|OwnerPartId=-1|Location.X=89|Location.Y=452|Color=8388608|FontID=1|IsHidden=T|Text=Tape and Reel|Name=Packaging
|RECORD=41|OwnerIndex=1272|IndexInSheet=7|OwnerPartId=-1|Location.X=89|Location.Y=452|Color=8388608|FontID=1|IsHidden=T|Text=10uF|Name=Capacitance
|RECORD=41|OwnerIndex=1272|IndexInSheet=8|OwnerPartId=-1|Location.X=89|Location.Y=452|Color=8388608|FontID=1|IsHidden=T|Text=25V|Name=Voltage Rating (DC)
|RECORD=41|OwnerIndex=1272|IndexInSheet=9|OwnerPartId=-1|Location.X=89|Location.Y=452|Color=8388608|FontID=1|IsHidden=T|Text=0.053inch|Name=Thickness
|RECORD=41|OwnerIndex=1272|IndexInSheet=10|OwnerPartId=-1|Location.X=89|Location.Y=452|Color=8388608|FontID=1|IsHidden=T|Text=Ceramic|Name=Resistor Type
|RECORD=41|OwnerIndex=1272|IndexInSheet=11|OwnerPartId=-1|Location.X=89|Location.Y=452|Color=8388608|FontID=1|IsHidden=T|Text=Yes|Name=RoHS Compliant
|RECORD=41|OwnerIndex=1272|IndexInSheet=12|OwnerPartId=-1|Location.X=89|Location.Y=452|Color=8388608|FontID=1|IsHidden=T|Text=Lead Free|Name=Lead Free
|RECORD=41|OwnerIndex=1272|IndexInSheet=13|OwnerPartId=-1|Location.X=89|Location.Y=452|Color=8388608|FontID=1|IsHidden=T|Text=No SVHC|Name=REACH SVHC
|RECORD=41|OwnerIndex=1272|IndexInSheet=14|OwnerPartId=-1|Location.X=89|Location.Y=452|Color=8388608|FontID=1|IsHidden=T|Text=2|Name=Number of Pins
|RECORD=41|OwnerIndex=1272|IndexInSheet=15|OwnerPartId=-1|Location.X=89|Location.Y=452|Color=8388608|FontID=1|IsHidden=T|Text=1|Name=Package Quantity
|RECORD=41|OwnerIndex=1272|IndexInSheet=16|OwnerPartId=-1|Location.X=89|Location.Y=452|Color=8388608|FontID=1|IsHidden=T|Text=Surface Mount|Name=Mount
|RECORD=41|OwnerIndex=1272|IndexInSheet=17|OwnerPartId=-1|Location.X=89|Location.Y=452|Color=8388608|FontID=1|IsHidden=T|Text=SMD/SMT|Name=Termination
|RECORD=41|OwnerIndex=1272|IndexInSheet=18|OwnerPartId=-1|Location.X=89|Location.Y=452|Color=8388608|FontID=1|IsHidden=T|Text=0.049inch|Name=Width
|RECORD=41|OwnerIndex=1272|IndexInSheet=19|OwnerPartId=-1|Location.X=89|Location.Y=452|Color=8388608|FontID=1|IsHidden=T|Text=85°C|Name=Max Operating Temperature
|RECORD=41|OwnerIndex=1272|IndexInSheet=20|OwnerPartId=-1|Location.X=89|Location.Y=452|Color=8388608|FontID=1|IsHidden=T|Text=0.079inch|Name=Length
|RECORD=41|OwnerIndex=1272|IndexInSheet=21|OwnerPartId=-1|Location.X=89|Location.Y=452|Color=8388608|FontID=1|IsHidden=T|Text=0805|Name=Case/Package
|RECORD=41|OwnerIndex=1272|IndexInSheet=22|OwnerPartId=-1|Location.X=89|Location.Y=452|Color=8388608|FontID=1|IsHidden=T|Text=25V|Name=Voltage Rating
|RECORD=41|OwnerIndex=1272|IndexInSheet=23|OwnerPartId=-1|Location.X=89|Location.Y=452|Color=8388608|FontID=1|IsHidden=T|Text=-55°C|Name=Min Operating Temperature
|RECORD=41|OwnerIndex=1272|IndexInSheet=24|OwnerPartId=-1|Location.X=89|Location.Y=452|Color=8388608|FontID=1|IsHidden=T|Text=10%|Name=Tolerance
|RECORD=41|OwnerIndex=1272|IndexInSheet=25|OwnerPartId=-1|Location.X=89|Location.Y=452|Color=8388608|FontID=1|IsHidden=T|Text=X7R|Name=Dielectric
|RECORD=41|OwnerIndex=1272|IndexInSheet=26|OwnerPartId=-1|Location.X=89|Location.Y=452|Color=8388608|FontID=1|IsHidden=T|Text=2012|Name=Case Code (Metric)
|RECORD=41|OwnerIndex=1272|IndexInSheet=27|OwnerPartId=-1|Location.X=89|Location.Y=452|Color=8388608|FontID=1|IsHidden=T|Text=0805|Name=Case Code (Imperial)
|RECORD=41|OwnerIndex=1272|IndexInSheet=28|OwnerPartId=-1|Location.X=89|Location.Y=452|Color=8388608|FontID=1|IsHidden=T|Text=1.25mm|Name=Height
|RECORD=41|OwnerIndex=1272|IndexInSheet=29|OwnerPartId=-1|Location.X=89|Location.Y=452|Color=8388608|FontID=1|IsHidden=T|Text=16V|Name=Voltage
|RECORD=41|OwnerIndex=1272|IndexInSheet=30|OwnerPartId=-1|Location.X=89|Location.Y=452|Color=8388608|FontID=1|IsHidden=T|Text=M|Name=Series
|RECORD=34|OwnerIndex=1272|IndexInSheet=-1|OwnerPartId=-1|Location.X=111|Location.Y=437|Color=8388608|FontID=1|Text=C55|Name=Designator|ReadOnlyState=1
|RECORD=41|OwnerIndex=1272|IndexInSheet=-1|OwnerPartId=1|Location.X=111|Location.Y=427|Color=8388608|FontID=1|Text=10uF|Name=Comment
|RECORD=44|OwnerIndex=1272
|RECORD=45|OwnerIndex=1308|IndexInSheet=-1|UseComponentLibrary=T|ModelName=FP-MK212BG-MFG|ModelType=PCBLIB|DatafileCount=1|ModelDatafileEntity0=FP-MK212BG-MFG|ModelDatafileKind0=PCBLib|IsCurrent=T|DatalinksLocked=T|DatabaseDatalinksLocked=T
|RECORD=46|OwnerIndex=1309
|RECORD=48|OwnerIndex=1309
|RECORD=45|OwnerIndex=1308|IndexInSheet=-1|UseComponentLibrary=T|ModelName=FP-MK212BG-IPC_C|ModelType=PCBLIB|DatafileCount=1|ModelDatafileEntity0=FP-MK212BG-IPC_C|ModelDatafileKind0=PCBLib|DatalinksLocked=T|DatabaseDatalinksLocked=T
|RECORD=46|OwnerIndex=1312
|RECORD=48|OwnerIndex=1312
|RECORD=45|OwnerIndex=1308|IndexInSheet=-1|UseComponentLibrary=T|ModelName=FP-MK212BG-IPC_B|ModelType=PCBLIB|DatafileCount=1|ModelDatafileEntity0=FP-MK212BG-IPC_B|ModelDatafileKind0=PCBLib|DatalinksLocked=T|DatabaseDatalinksLocked=T
|RECORD=46|OwnerIndex=1315
|RECORD=48|OwnerIndex=1315
|RECORD=45|OwnerIndex=1308|IndexInSheet=-1|UseComponentLibrary=T|ModelName=FP-MK212BG-IPC_A|ModelType=PCBLIB|DatafileCount=1|ModelDatafileEntity0=FP-MK212BG-IPC_A|ModelDatafileKind0=PCBLib|DatalinksLocked=T|DatabaseDatalinksLocked=T
|RECORD=46|OwnerIndex=1318
|RECORD=48|OwnerIndex=1318
|RECORD=45|OwnerIndex=1308|IndexInSheet=-1|UseComponentLibrary=T|ModelName=TMK212BBJ106_G-T|ModelType=SIM|IsCurrent=T|DatalinksLocked=T|DatabaseDatalinksLocked=T
|RECORD=46|OwnerIndex=1321
|RECORD=48|OwnerIndex=1321
|RECORD=41|OwnerIndex=1323|IndexInSheet=-1|OwnerPartId=-1|Color=8388608|FontID=1|IsHidden=T|Text=General|Name=Kind
|RECORD=41|OwnerIndex=1323|IndexInSheet=-1|OwnerPartId=-1|Color=8388608|FontID=1|IsHidden=T|Text=Spice Subcircuit|Name=SubKind
|RECORD=41|OwnerIndex=1323|IndexInSheet=-1|OwnerPartId=-1|Color=8388608|FontID=1|IsHidden=T|Name=Spice Prefix
|RECORD=41|OwnerIndex=1323|IndexInSheet=-1|OwnerPartId=-1|Color=8388608|FontID=1|IsHidden=T|Name=Excluded Parts
|RECORD=41|OwnerIndex=1323|IndexInSheet=-1|OwnerPartId=-1|Color=8388608|FontID=1|IsHidden=T|Name=Netlist
|RECORD=1|LibReference=b4654b650e69147ec39a6b967a45e02|ComponentDescription=None|PartCount=2|DisplayModeCount=1|IndexInSheet=146|OwnerPartId=-1|Location.X=200|Location.Y=450|CurrentPartId=1|LibraryPath=*|SourceLibraryName=Altium Content Vault|TargetFileName=*|AreaColor=11599871|Color=128|PartIDLocked=T|DesignItemId=CMP-14477-000079-2|AllPinCount=2
|RECORD=2|OwnerIndex=1329|OwnerPartId=1|Electrical=4|PinConglomerate=49|PinLength=7|Location.X=200|Location.Y=443|Name=1|Designator=1|PinPropagationDelay=0.000000E+000
|RECORD=2|OwnerIndex=1329|OwnerPartId=1|Electrical=4|PinConglomerate=51|PinLength=6|Location.X=200|Location.Y=436|Name=2|Designator=2|PinPropagationDelay=0.000000E+000
|RECORD=13|OwnerIndex=1329|IsNotAccesible=T|IndexInSheet=2|OwnerPartId=1|Location.X=210|Location.Y=443|Corner.X=190|Corner.Y=443|LineWidth=1|Color=16711680
|RECORD=13|OwnerIndex=1329|IsNotAccesible=T|IndexInSheet=3|OwnerPartId=1|Location.X=210|Location.Y=437|Corner.X=190|Corner.Y=437|LineWidth=1|Color=16711680
|RECORD=13|OwnerIndex=1329|IsNotAccesible=T|IndexInSheet=4|OwnerPartId=1|Location.X=200|Location.Y=443|Corner.X=200|Corner.Y=446|LineWidth=1|Color=16711680
|RECORD=13|OwnerIndex=1329|IsNotAccesible=T|IndexInSheet=5|OwnerPartId=1|Location.X=200|Location.Y=436|Corner.X=200|Corner.Y=435|LineWidth=1|Color=16711680
|RECORD=41|OwnerIndex=1329|IndexInSheet=6|OwnerPartId=-1|Location.X=189|Location.Y=452|Color=8388608|FontID=1|IsHidden=T|Text=Tape and Reel|Name=Packaging
|RECORD=41|OwnerIndex=1329|IndexInSheet=7|OwnerPartId=-1|Location.X=189|Location.Y=452|Color=8388608|FontID=1|IsHidden=T|Text=10uF|Name=Capacitance
|RECORD=41|OwnerIndex=1329|IndexInSheet=8|OwnerPartId=-1|Location.X=189|Location.Y=452|Color=8388608|FontID=1|IsHidden=T|Text=25V|Name=Voltage Rating (DC)
|RECORD=41|OwnerIndex=1329|IndexInSheet=9|OwnerPartId=-1|Location.X=189|Location.Y=452|Color=8388608|FontID=1|IsHidden=T|Text=0.053inch|Name=Thickness
|RECORD=41|OwnerIndex=1329|IndexInSheet=10|OwnerPartId=-1|Location.X=189|Location.Y=452|Color=8388608|FontID=1|IsHidden=T|Text=Ceramic|Name=Resistor Type
|RECORD=41|OwnerIndex=1329|IndexInSheet=11|OwnerPartId=-1|Location.X=189|Location.Y=452|Color=8388608|FontID=1|IsHidden=T|Text=Yes|Name=RoHS Compliant
|RECORD=41|OwnerIndex=1329|IndexInSheet=12|OwnerPartId=-1|Location.X=189|Location.Y=452|Color=8388608|FontID=1|IsHidden=T|Text=Lead Free|Name=Lead Free
|RECORD=41|OwnerIndex=1329|IndexInSheet=13|OwnerPartId=-1|Location.X=189|Location.Y=452|Color=8388608|FontID=1|IsHidden=T|Text=No SVHC|Name=REACH SVHC
|RECORD=41|OwnerIndex=1329|IndexInSheet=14|OwnerPartId=-1|Location.X=189|Location.Y=452|Color=8388608|FontID=1|IsHidden=T|Text=2|Name=Number of Pins
|RECORD=41|OwnerIndex=1329|IndexInSheet=15|OwnerPartId=-1|Location.X=189|Location.Y=452|Color=8388608|FontID=1|IsHidden=T|Text=1|Name=Package Quantity
|RECORD=41|OwnerIndex=1329|IndexInSheet=16|OwnerPartId=-1|Location.X=189|Location.Y=452|Color=8388608|FontID=1|IsHidden=T|Text=Surface Mount|Name=Mount
|RECORD=41|OwnerIndex=1329|IndexInSheet=17|OwnerPartId=-1|Location.X=189|Location.Y=452|Color=8388608|FontID=1|IsHidden=T|Text=SMD/SMT|Name=Termination
|RECORD=41|OwnerIndex=1329|IndexInSheet=18|OwnerPartId=-1|Location.X=189|Location.Y=452|Color=8388608|FontID=1|IsHidden=T|Text=0.049inch|Name=Width
|RECORD=41|OwnerIndex=1329|IndexInSheet=19|OwnerPartId=-1|Location.X=189|Location.Y=452|Color=8388608|FontID=1|IsHidden=T|Text=85°C|Name=Max Operating Temperature
|RECORD=41|OwnerIndex=1329|IndexInSheet=20|OwnerPartId=-1|Location.X=189|Location.Y=452|Color=8388608|FontID=1|IsHidden=T|Text=0.079inch|Name=Length
|RECORD=41|OwnerIndex=1329|IndexInSheet=21|OwnerPartId=-1|Location.X=189|Location.Y=452|Color=8388608|FontID=1|IsHidden=T|Text=0805|Name=Case/Package
|RECORD=41|OwnerIndex=1329|IndexInSheet=22|OwnerPartId=-1|Location.X=189|Location.Y=452|Color=8388608|FontID=1|IsHidden=T|Text=25V|Name=Voltage Rating
|RECORD=41|OwnerIndex=1329|IndexInSheet=23|OwnerPartId=-1|Location.X=189|Location.Y=452|Color=8388608|FontID=1|IsHidden=T|Text=-55°C|Name=Min Operating Temperature
|RECORD=41|OwnerIndex=1329|IndexInSheet=24|OwnerPartId=-1|Location.X=189|Location.Y=452|Color=8388608|FontID=1|IsHidden=T|Text=10%|Name=Tolerance
|RECORD=41|OwnerIndex=1329|IndexInSheet=25|OwnerPartId=-1|Location.X=189|Location.Y=452|Color=8388608|FontID=1|IsHidden=T|Text=X7R|Name=Dielectric
|RECORD=41|OwnerIndex=1329|IndexInSheet=26|OwnerPartId=-1|Location.X=189|Location.Y=452|Color=8388608|FontID=1|IsHidden=T|Text=2012|Name=Case Code (Metric)
|RECORD=41|OwnerIndex=1329|IndexInSheet=27|OwnerPartId=-1|Location.X=189|Location.Y=452|Color=8388608|FontID=1|IsHidden=T|Text=0805|Name=Case Code (Imperial)
|RECORD=41|OwnerIndex=1329|IndexInSheet=28|OwnerPartId=-1|Location.X=189|Location.Y=452|Color=8388608|FontID=1|IsHidden=T|Text=1.25mm|Name=Height
|RECORD=41|OwnerIndex=1329|IndexInSheet=29|OwnerPartId=-1|Location.X=189|Location.Y=452|Color=8388608|FontID=1|IsHidden=T|Text=16V|Name=Voltage
|RECORD=41|OwnerIndex=1329|IndexInSheet=30|OwnerPartId=-1|Location.X=189|Location.Y=452|Color=8388608|FontID=1|IsHidden=T|Text=M|Name=Series
|RECORD=34|OwnerIndex=1329|IndexInSheet=-1|OwnerPartId=-1|Location.X=211|Location.Y=437|Color=8388608|FontID=1|Text=C56|Name=Designator|ReadOnlyState=1
|RECORD=41|OwnerIndex=1329|IndexInSheet=-1|OwnerPartId=1|Location.X=211|Location.Y=427|Color=8388608|FontID=1|Text=10uF|Name=Comment
|RECORD=44|OwnerIndex=1329
|RECORD=45|OwnerIndex=1365|IndexInSheet=-1|UseComponentLibrary=T|ModelName=FP-MK212BG-MFG|ModelType=PCBLIB|DatafileCount=1|ModelDatafileEntity0=FP-MK212BG-MFG|ModelDatafileKind0=PCBLib|IsCurrent=T|DatalinksLocked=T|DatabaseDatalinksLocked=T
|RECORD=46|OwnerIndex=1366
|RECORD=48|OwnerIndex=1366
|RECORD=45|OwnerIndex=1365|IndexInSheet=-1|UseComponentLibrary=T|ModelName=FP-MK212BG-IPC_C|ModelType=PCBLIB|DatafileCount=1|ModelDatafileEntity0=FP-MK212BG-IPC_C|ModelDatafileKind0=PCBLib|DatalinksLocked=T|DatabaseDatalinksLocked=T
|RECORD=46|OwnerIndex=1369
|RECORD=48|OwnerIndex=1369
|RECORD=45|OwnerIndex=1365|IndexInSheet=-1|UseComponentLibrary=T|ModelName=FP-MK212BG-IPC_B|ModelType=PCBLIB|DatafileCount=1|ModelDatafileEntity0=FP-MK212BG-IPC_B|ModelDatafileKind0=PCBLib|DatalinksLocked=T|DatabaseDatalinksLocked=T
|RECORD=46|OwnerIndex=1372
|RECORD=48|OwnerIndex=1372
|RECORD=45|OwnerIndex=1365|IndexInSheet=-1|UseComponentLibrary=T|ModelName=FP-MK212BG-IPC_A|ModelType=PCBLIB|DatafileCount=1|ModelDatafileEntity0=FP-MK212BG-IPC_A|ModelDatafileKind0=PCBLib|DatalinksLocked=T|DatabaseDatalinksLocked=T
|RECORD=46|OwnerIndex=1375
|RECORD=48|OwnerIndex=1375
|RECORD=45|OwnerIndex=1365|IndexInSheet=-1|UseComponentLibrary=T|ModelName=TMK212BBJ106_G-T|ModelType=SIM|IsCurrent=T|DatalinksLocked=T|DatabaseDatalinksLocked=T
|RECORD=46|OwnerIndex=1378
|RECORD=48|OwnerIndex=1378
|RECORD=41|OwnerIndex=1380|IndexInSheet=-1|OwnerPartId=-1|Color=8388608|FontID=1|IsHidden=T|Text=General|Name=Kind
|RECORD=41|OwnerIndex=1380|IndexInSheet=-1|OwnerPartId=-1|Color=8388608|FontID=1|IsHidden=T|Text=Spice Subcircuit|Name=SubKind
|RECORD=41|OwnerIndex=1380|IndexInSheet=-1|OwnerPartId=-1|Color=8388608|FontID=1|IsHidden=T|Name=Spice Prefix
|RECORD=41|OwnerIndex=1380|IndexInSheet=-1|OwnerPartId=-1|Color=8388608|FontID=1|IsHidden=T|Name=Excluded Parts
|RECORD=41|OwnerIndex=1380|IndexInSheet=-1|OwnerPartId=-1|Color=8388608|FontID=1|IsHidden=T|Name=Netlist
|RECORD=17|IndexInSheet=147|OwnerPartId=-1|Style=4|ShowNetName=T|Location.X=590|Location.Y=410|Orientation=3|Color=128|FontID=1|Text=GND
|RECORD=17|IndexInSheet=148|OwnerPartId=-1|Style=4|ShowNetName=T|Location.X=680|Location.Y=930|Orientation=3|Color=128|FontID=1|Text=GND
|RECORD=17|IndexInSheet=149|OwnerPartId=-1|ShowNetName=T|Location.X=220|Location.Y=1000|Orientation=1|Color=128|FontID=1|Text=+5.0V
|RECORD=17|IndexInSheet=150|OwnerPartId=-1|ShowNetName=T|Location.X=120|Location.Y=1000|Orientation=1|Color=128|FontID=1|Text=+3.3V
|RECORD=17|IndexInSheet=151|OwnerPartId=-1|Style=4|ShowNetName=T|Location.X=120|Location.Y=920|Orientation=3|Color=128|FontID=1|Text=GND
|RECORD=17|IndexInSheet=152|OwnerPartId=-1|Style=4|ShowNetName=T|Location.X=220|Location.Y=920|Orientation=3|Color=128|FontID=1|Text=GND
|RECORD=1|LibReference=CAP|ComponentDescription=C0603X104K5RACAUTO|PartCount=2|DisplayModeCount=2|IndexInSheet=153|OwnerPartId=-1|Location.X=160|Location.Y=940|Orientation=1|CurrentPartId=1|SourceLibraryName=Altium Content Vault|TargetFileName=*|AreaColor=11599871|Color=128|PartIDLocked=F|DesignItemId=CMP-2006-00003-1|AllPinCount=2
|RECORD=2|OwnerIndex=1392|OwnerPartId=1|OwnerPartDisplayMode=1|FormalType=1|Electrical=4|PinConglomerate=35|PinLength=10|Location.X=170|Location.Y=940|Name=1|Designator=1|PinPropagationDelay=0.000000E+000
|RECORD=2|OwnerIndex=1392|OwnerPartId=1|OwnerPartDisplayMode=1|FormalType=1|Electrical=4|PinConglomerate=33|PinLength=10|Location.X=170|Location.Y=950|Name=2|Designator=2|PinPropagationDelay=0.000000E+000
|RECORD=13|OwnerIndex=1392|IsNotAccesible=T|IndexInSheet=2|OwnerPartId=1|OwnerPartDisplayMode=1|Location.X=178|Location.Y=940|Corner.X=162|Corner.Y=940|LineWidth=1|Color=16711680
|RECORD=13|OwnerIndex=1392|IsNotAccesible=T|IndexInSheet=3|OwnerPartId=1|OwnerPartDisplayMode=1|Location.X=170|Location.Y=944|Corner.X=170|Corner.Y=950|LineWidth=1|Color=16711680
|RECORD=12|OwnerIndex=1392|IsNotAccesible=T|IndexInSheet=4|OwnerPartId=1|OwnerPartDisplayMode=1|Location.X=170|Location.Y=960|Radius=16|LineWidth=1|StartAngle=241.000|EndAngle=270.000|Color=16711680
|RECORD=12|OwnerIndex=1392|IsNotAccesible=T|IndexInSheet=5|OwnerPartId=1|OwnerPartDisplayMode=1|Location.X=170|Location.Y=960|Radius=16|LineWidth=1|StartAngle=270.000|EndAngle=299.000|Color=16711680
|RECORD=2|OwnerIndex=1392|OwnerPartId=1|FormalType=1|Electrical=4|PinConglomerate=35|PinLength=10|Location.X=170|Location.Y=940|Name=1|Designator=1|PinPropagationDelay=0.000000E+000
|RECORD=2|OwnerIndex=1392|OwnerPartId=1|FormalType=1|Electrical=4|PinConglomerate=33|PinLength=10|Location.X=170|Location.Y=950|Name=2|Designator=2|PinPropagationDelay=0.000000E+000
|RECORD=13|OwnerIndex=1392|IsNotAccesible=T|IndexInSheet=8|OwnerPartId=1|Location.X=162|Location.Y=947|Corner.X=178|Corner.Y=947|LineWidth=1|Color=16711680
|RECORD=13|OwnerIndex=1392|IsNotAccesible=T|IndexInSheet=9|OwnerPartId=1|Location.X=178|Location.Y=943|Corner.X=162|Corner.Y=943|LineWidth=1|Color=16711680
|RECORD=6|OwnerIndex=1392|IsNotAccesible=T|IndexInSheet=10|OwnerPartId=1|LineWidth=1|Color=16711680|LocationCount=2|X1=170|Y1=940|X2=170|Y2=943
|RECORD=6|OwnerIndex=1392|IsNotAccesible=T|IndexInSheet=11|OwnerPartId=1|LineWidth=1|Color=16711680|LocationCount=2|X1=170|Y1=950|X2=170|Y2=947
|RECORD=41|OwnerIndex=1392|IndexInSheet=12|OwnerPartId=-1|Location.X=161|Location.Y=962|Color=8388608|FontID=1|IsHidden=T|Text=Kemet|Name=Manufacturer
|RECORD=41|OwnerIndex=1392|IndexInSheet=13|OwnerPartId=-1|Location.X=161|Location.Y=962|Color=8388608|FontID=1|IsHidden=T|Text=C0603X104K5RACAUTO|Name=Part Number
|RECORD=34|OwnerIndex=1392|IndexInSheet=-1|OwnerPartId=-1|Location.X=179|Location.Y=941|Color=8388608|FontID=1|Text=C43|Name=Designator|ReadOnlyState=1
|RECORD=41|OwnerIndex=1392|IndexInSheet=-1|OwnerPartId=-1|Location.X=179|Location.Y=931|Color=8388608|FontID=1|Text=0.1uF|Name=Comment
|RECORD=44|OwnerIndex=1392
|RECORD=45|OwnerIndex=1413|IndexInSheet=-1|Description=Chip Capacitor, 2-Leads, Body 1.60x0.80mm, IPC Low Density|UseComponentLibrary=T|ModelName=CAPC1608X87X45ML20T05|ModelType=PCBLIB|DatafileCount=1|ModelDatafileEntity0=CAPC1608X87X45ML20T05|ModelDatafileKind0=PCBLib|IsCurrent=T|DatalinksLocked=T|DatabaseDatalinksLocked=T
|RECORD=46|OwnerIndex=1414
|RECORD=48|OwnerIndex=1414
|RECORD=41|OwnerIndex=1416|IndexInSheet=-1|OwnerPartId=-1|Color=8388608|FontID=1|Text=2D|Name=Available Preview Images
|RECORD=45|OwnerIndex=1413|IndexInSheet=-1|Description=Chip Capacitor, 2-Leads, Body 1.60x0.80mm, IPC High Density|UseComponentLibrary=T|ModelName=CAPC1608X87X45LL20T05|ModelType=PCBLIB|DatafileCount=1|ModelDatafileEntity0=CAPC1608X87X45LL20T05|ModelDatafileKind0=PCBLib|DatalinksLocked=T|DatabaseDatalinksLocked=T
|RECORD=46|OwnerIndex=1418
|RECORD=48|OwnerIndex=1418
|RECORD=41|OwnerIndex=1420|IndexInSheet=-1|OwnerPartId=-1|Color=8388608|FontID=1|Text=2D|Name=Available Preview Images
|RECORD=45|OwnerIndex=1413|IndexInSheet=-1|Description=Chip Capacitor, 2-Leads, Body 1.60x0.80mm, IPC Medium Density|UseComponentLibrary=T|ModelName=CAPC1608X87X45NL20T05|ModelType=PCBLIB|DatafileCount=1|ModelDatafileEntity0=CAPC1608X87X45NL20T05|ModelDatafileKind0=PCBLib|DatalinksLocked=T|DatabaseDatalinksLocked=T
|RECORD=46|OwnerIndex=1422
|RECORD=48|OwnerIndex=1422
|RECORD=41|OwnerIndex=1424|IndexInSheet=-1|OwnerPartId=-1|Color=8388608|FontID=1|Text=2D|Name=Available Preview Images
|RECORD=1|LibReference=CAP|ComponentDescription=C0603X104K5RACAUTO|PartCount=2|DisplayModeCount=2|IndexInSheet=154|OwnerPartId=-1|Location.X=260|Location.Y=940|Orientation=1|CurrentPartId=1|SourceLibraryName=Altium Content Vault|TargetFileName=*|AreaColor=11599871|Color=128|PartIDLocked=F|DesignItemId=CMP-2006-00003-1|AllPinCount=2
|RECORD=2|OwnerIndex=1426|OwnerPartId=1|OwnerPartDisplayMode=1|FormalType=1|Electrical=4|PinConglomerate=35|PinLength=10|Location.X=270|Location.Y=940|Name=1|Designator=1|PinPropagationDelay=0.000000E+000
|RECORD=2|OwnerIndex=1426|OwnerPartId=1|OwnerPartDisplayMode=1|FormalType=1|Electrical=4|PinConglomerate=33|PinLength=10|Location.X=270|Location.Y=950|Name=2|Designator=2|PinPropagationDelay=0.000000E+000
|RECORD=13|OwnerIndex=1426|IsNotAccesible=T|IndexInSheet=2|OwnerPartId=1|OwnerPartDisplayMode=1|Location.X=278|Location.Y=940|Corner.X=262|Corner.Y=940|LineWidth=1|Color=16711680
|RECORD=13|OwnerIndex=1426|IsNotAccesible=T|IndexInSheet=3|OwnerPartId=1|OwnerPartDisplayMode=1|Location.X=270|Location.Y=944|Corner.X=270|Corner.Y=950|LineWidth=1|Color=16711680
|RECORD=12|OwnerIndex=1426|IsNotAccesible=T|IndexInSheet=4|OwnerPartId=1|OwnerPartDisplayMode=1|Location.X=270|Location.Y=960|Radius=16|LineWidth=1|StartAngle=241.000|EndAngle=270.000|Color=16711680
|RECORD=12|OwnerIndex=1426|IsNotAccesible=T|IndexInSheet=5|OwnerPartId=1|OwnerPartDisplayMode=1|Location.X=270|Location.Y=960|Radius=16|LineWidth=1|StartAngle=270.000|EndAngle=299.000|Color=16711680
|RECORD=2|OwnerIndex=1426|OwnerPartId=1|FormalType=1|Electrical=4|PinConglomerate=35|PinLength=10|Location.X=270|Location.Y=940|Name=1|Designator=1|PinPropagationDelay=0.000000E+000
|RECORD=2|OwnerIndex=1426|OwnerPartId=1|FormalType=1|Electrical=4|PinConglomerate=33|PinLength=10|Location.X=270|Location.Y=950|Name=2|Designator=2|PinPropagationDelay=0.000000E+000
|RECORD=13|OwnerIndex=1426|IsNotAccesible=T|IndexInSheet=8|OwnerPartId=1|Location.X=262|Location.Y=947|Corner.X=278|Corner.Y=947|LineWidth=1|Color=16711680
|RECORD=13|OwnerIndex=1426|IsNotAccesible=T|IndexInSheet=9|OwnerPartId=1|Location.X=278|Location.Y=943|Corner.X=262|Corner.Y=943|LineWidth=1|Color=16711680
|RECORD=6|OwnerIndex=1426|IsNotAccesible=T|IndexInSheet=10|OwnerPartId=1|LineWidth=1|Color=16711680|LocationCount=2|X1=270|Y1=940|X2=270|Y2=943
|RECORD=6|OwnerIndex=1426|IsNotAccesible=T|IndexInSheet=11|OwnerPartId=1|LineWidth=1|Color=16711680|LocationCount=2|X1=270|Y1=950|X2=270|Y2=947
|RECORD=41|OwnerIndex=1426|IndexInSheet=12|OwnerPartId=-1|Location.X=261|Location.Y=962|Color=8388608|FontID=1|IsHidden=T|Text=Kemet|Name=Manufacturer
|RECORD=41|OwnerIndex=1426|IndexInSheet=13|OwnerPartId=-1|Location.X=261|Location.Y=962|Color=8388608|FontID=1|IsHidden=T|Text=C0603X104K5RACAUTO|Name=Part Number
|RECORD=34|OwnerIndex=1426|IndexInSheet=-1|OwnerPartId=-1|Location.X=279|Location.Y=941|Color=8388608|FontID=1|Text=C54|Name=Designator|ReadOnlyState=1
|RECORD=41|OwnerIndex=1426|IndexInSheet=-1|OwnerPartId=-1|Location.X=279|Location.Y=931|Color=8388608|FontID=1|Text=0.1uF|Name=Comment
|RECORD=44|OwnerIndex=1426
|RECORD=45|OwnerIndex=1447|IndexInSheet=-1|Description=Chip Capacitor, 2-Leads, Body 1.60x0.80mm, IPC Low Density|UseComponentLibrary=T|ModelName=CAPC1608X87X45ML20T05|ModelType=PCBLIB|DatafileCount=1|ModelDatafileEntity0=CAPC1608X87X45ML20T05|ModelDatafileKind0=PCBLib|IsCurrent=T|DatalinksLocked=T|DatabaseDatalinksLocked=T
|RECORD=46|OwnerIndex=1448
|RECORD=48|OwnerIndex=1448
|RECORD=41|OwnerIndex=1450|IndexInSheet=-1|OwnerPartId=-1|Color=8388608|FontID=1|Text=2D|Name=Available Preview Images
|RECORD=45|OwnerIndex=1447|IndexInSheet=-1|Description=Chip Capacitor, 2-Leads, Body 1.60x0.80mm, IPC High Density|UseComponentLibrary=T|ModelName=CAPC1608X87X45LL20T05|ModelType=PCBLIB|DatafileCount=1|ModelDatafileEntity0=CAPC1608X87X45LL20T05|ModelDatafileKind0=PCBLib|DatalinksLocked=T|DatabaseDatalinksLocked=T
|RECORD=46|OwnerIndex=1452
|RECORD=48|OwnerIndex=1452
|RECORD=41|OwnerIndex=1454|IndexInSheet=-1|OwnerPartId=-1|Color=8388608|FontID=1|Text=2D|Name=Available Preview Images
|RECORD=45|OwnerIndex=1447|IndexInSheet=-1|Description=Chip Capacitor, 2-Leads, Body 1.60x0.80mm, IPC Medium Density|UseComponentLibrary=T|ModelName=CAPC1608X87X45NL20T05|ModelType=PCBLIB|DatafileCount=1|ModelDatafileEntity0=CAPC1608X87X45NL20T05|ModelDatafileKind0=PCBLib|DatalinksLocked=T|DatabaseDatalinksLocked=T
|RECORD=46|OwnerIndex=1456
|RECORD=48|OwnerIndex=1456
|RECORD=41|OwnerIndex=1458|IndexInSheet=-1|OwnerPartId=-1|Color=8388608|FontID=1|Text=2D|Name=Available Preview Images
|RECORD=1|LibReference=b4654b650e69147ec39a6b967a45e02|ComponentDescription=None|PartCount=2|DisplayModeCount=1|IndexInSheet=155|OwnerPartId=-1|Location.X=120|Location.Y=960|CurrentPartId=1|LibraryPath=*|SourceLibraryName=Altium Content Vault|TargetFileName=*|AreaColor=11599871|Color=128|PartIDLocked=T|DesignItemId=CMP-14477-000079-2|AllPinCount=2
|RECORD=2|OwnerIndex=1460|OwnerPartId=1|Electrical=4|PinConglomerate=49|PinLength=7|Location.X=120|Location.Y=953|Name=1|Designator=1|PinPropagationDelay=0.000000E+000
|RECORD=2|OwnerIndex=1460|OwnerPartId=1|Electrical=4|PinConglomerate=51|PinLength=6|Location.X=120|Location.Y=946|Name=2|Designator=2|PinPropagationDelay=0.000000E+000
|RECORD=13|OwnerIndex=1460|IsNotAccesible=T|IndexInSheet=2|OwnerPartId=1|Location.X=130|Location.Y=953|Corner.X=110|Corner.Y=953|LineWidth=1|Color=16711680
|RECORD=13|OwnerIndex=1460|IsNotAccesible=T|IndexInSheet=3|OwnerPartId=1|Location.X=130|Location.Y=947|Corner.X=110|Corner.Y=947|LineWidth=1|Color=16711680
|RECORD=13|OwnerIndex=1460|IsNotAccesible=T|IndexInSheet=4|OwnerPartId=1|Location.X=120|Location.Y=953|Corner.X=120|Corner.Y=956|LineWidth=1|Color=16711680
|RECORD=13|OwnerIndex=1460|IsNotAccesible=T|IndexInSheet=5|OwnerPartId=1|Location.X=120|Location.Y=946|Corner.X=120|Corner.Y=945|LineWidth=1|Color=16711680
|RECORD=41|OwnerIndex=1460|IndexInSheet=6|OwnerPartId=-1|Location.X=109|Location.Y=962|Color=8388608|FontID=1|IsHidden=T|Text=Tape and Reel|Name=Packaging
|RECORD=41|OwnerIndex=1460|IndexInSheet=7|OwnerPartId=-1|Location.X=109|Location.Y=962|Color=8388608|FontID=1|IsHidden=T|Text=10uF|Name=Capacitance
|RECORD=41|OwnerIndex=1460|IndexInSheet=8|OwnerPartId=-1|Location.X=109|Location.Y=962|Color=8388608|FontID=1|IsHidden=T|Text=25V|Name=Voltage Rating (DC)
|RECORD=41|OwnerIndex=1460|IndexInSheet=9|OwnerPartId=-1|Location.X=109|Location.Y=962|Color=8388608|FontID=1|IsHidden=T|Text=0.053inch|Name=Thickness
|RECORD=41|OwnerIndex=1460|IndexInSheet=10|OwnerPartId=-1|Location.X=109|Location.Y=962|Color=8388608|FontID=1|IsHidden=T|Text=Ceramic|Name=Resistor Type
|RECORD=41|OwnerIndex=1460|IndexInSheet=11|OwnerPartId=-1|Location.X=109|Location.Y=962|Color=8388608|FontID=1|IsHidden=T|Text=Yes|Name=RoHS Compliant
|RECORD=41|OwnerIndex=1460|IndexInSheet=12|OwnerPartId=-1|Location.X=109|Location.Y=962|Color=8388608|FontID=1|IsHidden=T|Text=Lead Free|Name=Lead Free
|RECORD=41|OwnerIndex=1460|IndexInSheet=13|OwnerPartId=-1|Location.X=109|Location.Y=962|Color=8388608|FontID=1|IsHidden=T|Text=No SVHC|Name=REACH SVHC
|RECORD=41|OwnerIndex=1460|IndexInSheet=14|OwnerPartId=-1|Location.X=109|Location.Y=962|Color=8388608|FontID=1|IsHidden=T|Text=2|Name=Number of Pins
|RECORD=41|OwnerIndex=1460|IndexInSheet=15|OwnerPartId=-1|Location.X=109|Location.Y=962|Color=8388608|FontID=1|IsHidden=T|Text=1|Name=Package Quantity
|RECORD=41|OwnerIndex=1460|IndexInSheet=16|OwnerPartId=-1|Location.X=109|Location.Y=962|Color=8388608|FontID=1|IsHidden=T|Text=Surface Mount|Name=Mount
|RECORD=41|OwnerIndex=1460|IndexInSheet=17|OwnerPartId=-1|Location.X=109|Location.Y=962|Color=8388608|FontID=1|IsHidden=T|Text=SMD/SMT|Name=Termination
|RECORD=41|OwnerIndex=1460|IndexInSheet=18|OwnerPartId=-1|Location.X=109|Location.Y=962|Color=8388608|FontID=1|IsHidden=T|Text=0.049inch|Name=Width
|RECORD=41|OwnerIndex=1460|IndexInSheet=19|OwnerPartId=-1|Location.X=109|Location.Y=962|Color=8388608|FontID=1|IsHidden=T|Text=85°C|Name=Max Operating Temperature
|RECORD=41|OwnerIndex=1460|IndexInSheet=20|OwnerPartId=-1|Location.X=109|Location.Y=962|Color=8388608|FontID=1|IsHidden=T|Text=0.079inch|Name=Length
|RECORD=41|OwnerIndex=1460|IndexInSheet=21|OwnerPartId=-1|Location.X=109|Location.Y=962|Color=8388608|FontID=1|IsHidden=T|Text=0805|Name=Case/Package
|RECORD=41|OwnerIndex=1460|IndexInSheet=22|OwnerPartId=-1|Location.X=109|Location.Y=962|Color=8388608|FontID=1|IsHidden=T|Text=25V|Name=Voltage Rating
|RECORD=41|OwnerIndex=1460|IndexInSheet=23|OwnerPartId=-1|Location.X=109|Location.Y=962|Color=8388608|FontID=1|IsHidden=T|Text=-55°C|Name=Min Operating Temperature
|RECORD=41|OwnerIndex=1460|IndexInSheet=24|OwnerPartId=-1|Location.X=109|Location.Y=962|Color=8388608|FontID=1|IsHidden=T|Text=10%|Name=Tolerance
|RECORD=41|OwnerIndex=1460|IndexInSheet=25|OwnerPartId=-1|Location.X=109|Location.Y=962|Color=8388608|FontID=1|IsHidden=T|Text=X7R|Name=Dielectric
|RECORD=41|OwnerIndex=1460|IndexInSheet=26|OwnerPartId=-1|Location.X=109|Location.Y=962|Color=8388608|FontID=1|IsHidden=T|Text=2012|Name=Case Code (Metric)
|RECORD=41|OwnerIndex=1460|IndexInSheet=27|OwnerPartId=-1|Location.X=109|Location.Y=962|Color=8388608|FontID=1|IsHidden=T|Text=0805|Name=Case Code (Imperial)
|RECORD=41|OwnerIndex=1460|IndexInSheet=28|OwnerPartId=-1|Location.X=109|Location.Y=962|Color=8388608|FontID=1|IsHidden=T|Text=1.25mm|Name=Height
|RECORD=41|OwnerIndex=1460|IndexInSheet=29|OwnerPartId=-1|Location.X=109|Location.Y=962|Color=8388608|FontID=1|IsHidden=T|Text=16V|Name=Voltage
|RECORD=41|OwnerIndex=1460|IndexInSheet=30|OwnerPartId=-1|Location.X=109|Location.Y=962|Color=8388608|FontID=1|IsHidden=T|Text=M|Name=Series
|RECORD=34|OwnerIndex=1460|IndexInSheet=-1|OwnerPartId=-1|Location.X=131|Location.Y=947|Color=8388608|FontID=1|Text=C41|Name=Designator|ReadOnlyState=1
|RECORD=41|OwnerIndex=1460|IndexInSheet=-1|OwnerPartId=1|Location.X=131|Location.Y=937|Color=8388608|FontID=1|Text=10uF|Name=Comment
|RECORD=44|OwnerIndex=1460
|RECORD=45|OwnerIndex=1496|IndexInSheet=-1|UseComponentLibrary=T|ModelName=FP-MK212BG-MFG|ModelType=PCBLIB|DatafileCount=1|ModelDatafileEntity0=FP-MK212BG-MFG|ModelDatafileKind0=PCBLib|IsCurrent=T|DatalinksLocked=T|DatabaseDatalinksLocked=T
|RECORD=46|OwnerIndex=1497
|RECORD=48|OwnerIndex=1497
|RECORD=45|OwnerIndex=1496|IndexInSheet=-1|UseComponentLibrary=T|ModelName=FP-MK212BG-IPC_C|ModelType=PCBLIB|DatafileCount=1|ModelDatafileEntity0=FP-MK212BG-IPC_C|ModelDatafileKind0=PCBLib|DatalinksLocked=T|DatabaseDatalinksLocked=T
|RECORD=46|OwnerIndex=1500
|RECORD=48|OwnerIndex=1500
|RECORD=45|OwnerIndex=1496|IndexInSheet=-1|UseComponentLibrary=T|ModelName=FP-MK212BG-IPC_B|ModelType=PCBLIB|DatafileCount=1|ModelDatafileEntity0=FP-MK212BG-IPC_B|ModelDatafileKind0=PCBLib|DatalinksLocked=T|DatabaseDatalinksLocked=T
|RECORD=46|OwnerIndex=1503
|RECORD=48|OwnerIndex=1503
|RECORD=45|OwnerIndex=1496|IndexInSheet=-1|UseComponentLibrary=T|ModelName=FP-MK212BG-IPC_A|ModelType=PCBLIB|DatafileCount=1|ModelDatafileEntity0=FP-MK212BG-IPC_A|ModelDatafileKind0=PCBLib|DatalinksLocked=T|DatabaseDatalinksLocked=T
|RECORD=46|OwnerIndex=1506
|RECORD=48|OwnerIndex=1506
|RECORD=45|OwnerIndex=1496|IndexInSheet=-1|UseComponentLibrary=T|ModelName=TMK212BBJ106_G-T|ModelType=SIM|IsCurrent=T|DatalinksLocked=T|DatabaseDatalinksLocked=T
|RECORD=46|OwnerIndex=1509
|RECORD=48|OwnerIndex=1509
|RECORD=41|OwnerIndex=1511|IndexInSheet=-1|OwnerPartId=-1|Color=8388608|FontID=1|IsHidden=T|Text=General|Name=Kind
|RECORD=41|OwnerIndex=1511|IndexInSheet=-1|OwnerPartId=-1|Color=8388608|FontID=1|IsHidden=T|Text=Spice Subcircuit|Name=SubKind
|RECORD=41|OwnerIndex=1511|IndexInSheet=-1|OwnerPartId=-1|Color=8388608|FontID=1|IsHidden=T|Name=Spice Prefix
|RECORD=41|OwnerIndex=1511|IndexInSheet=-1|OwnerPartId=-1|Color=8388608|FontID=1|IsHidden=T|Name=Excluded Parts
|RECORD=41|OwnerIndex=1511|IndexInSheet=-1|OwnerPartId=-1|Color=8388608|FontID=1|IsHidden=T|Name=Netlist
|RECORD=1|LibReference=b4654b650e69147ec39a6b967a45e02|ComponentDescription=None|PartCount=2|DisplayModeCount=1|IndexInSheet=156|OwnerPartId=-1|Location.X=220|Location.Y=960|CurrentPartId=1|LibraryPath=*|SourceLibraryName=Altium Content Vault|TargetFileName=*|AreaColor=11599871|Color=128|PartIDLocked=T|DesignItemId=CMP-14477-000079-2|AllPinCount=2
|RECORD=2|OwnerIndex=1517|OwnerPartId=1|Electrical=4|PinConglomerate=49|PinLength=7|Location.X=220|Location.Y=953|Name=1|Designator=1|PinPropagationDelay=0.000000E+000
|RECORD=2|OwnerIndex=1517|OwnerPartId=1|Electrical=4|PinConglomerate=51|PinLength=6|Location.X=220|Location.Y=946|Name=2|Designator=2|PinPropagationDelay=0.000000E+000
|RECORD=13|OwnerIndex=1517|IsNotAccesible=T|IndexInSheet=2|OwnerPartId=1|Location.X=230|Location.Y=953|Corner.X=210|Corner.Y=953|LineWidth=1|Color=16711680
|RECORD=13|OwnerIndex=1517|IsNotAccesible=T|IndexInSheet=3|OwnerPartId=1|Location.X=230|Location.Y=947|Corner.X=210|Corner.Y=947|LineWidth=1|Color=16711680
|RECORD=13|OwnerIndex=1517|IsNotAccesible=T|IndexInSheet=4|OwnerPartId=1|Location.X=220|Location.Y=953|Corner.X=220|Corner.Y=956|LineWidth=1|Color=16711680
|RECORD=13|OwnerIndex=1517|IsNotAccesible=T|IndexInSheet=5|OwnerPartId=1|Location.X=220|Location.Y=946|Corner.X=220|Corner.Y=945|LineWidth=1|Color=16711680
|RECORD=41|OwnerIndex=1517|IndexInSheet=6|OwnerPartId=-1|Location.X=209|Location.Y=962|Color=8388608|FontID=1|IsHidden=T|Text=Tape and Reel|Name=Packaging
|RECORD=41|OwnerIndex=1517|IndexInSheet=7|OwnerPartId=-1|Location.X=209|Location.Y=962|Color=8388608|FontID=1|IsHidden=T|Text=10uF|Name=Capacitance
|RECORD=41|OwnerIndex=1517|IndexInSheet=8|OwnerPartId=-1|Location.X=209|Location.Y=962|Color=8388608|FontID=1|IsHidden=T|Text=25V|Name=Voltage Rating (DC)
|RECORD=41|OwnerIndex=1517|IndexInSheet=9|OwnerPartId=-1|Location.X=209|Location.Y=962|Color=8388608|FontID=1|IsHidden=T|Text=0.053inch|Name=Thickness
|RECORD=41|OwnerIndex=1517|IndexInSheet=10|OwnerPartId=-1|Location.X=209|Location.Y=962|Color=8388608|FontID=1|IsHidden=T|Text=Ceramic|Name=Resistor Type
|RECORD=41|OwnerIndex=1517|IndexInSheet=11|OwnerPartId=-1|Location.X=209|Location.Y=962|Color=8388608|FontID=1|IsHidden=T|Text=Yes|Name=RoHS Compliant
|RECORD=41|OwnerIndex=1517|IndexInSheet=12|OwnerPartId=-1|Location.X=209|Location.Y=962|Color=8388608|FontID=1|IsHidden=T|Text=Lead Free|Name=Lead Free
|RECORD=41|OwnerIndex=1517|IndexInSheet=13|OwnerPartId=-1|Location.X=209|Location.Y=962|Color=8388608|FontID=1|IsHidden=T|Text=No SVHC|Name=REACH SVHC
|RECORD=41|OwnerIndex=1517|IndexInSheet=14|OwnerPartId=-1|Location.X=209|Location.Y=962|Color=8388608|FontID=1|IsHidden=T|Text=2|Name=Number of Pins
|RECORD=41|OwnerIndex=1517|IndexInSheet=15|OwnerPartId=-1|Location.X=209|Location.Y=962|Color=8388608|FontID=1|IsHidden=T|Text=1|Name=Package Quantity
|RECORD=41|OwnerIndex=1517|IndexInSheet=16|OwnerPartId=-1|Location.X=209|Location.Y=962|Color=8388608|FontID=1|IsHidden=T|Text=Surface Mount|Name=Mount
|RECORD=41|OwnerIndex=1517|IndexInSheet=17|OwnerPartId=-1|Location.X=209|Location.Y=962|Color=8388608|FontID=1|IsHidden=T|Text=SMD/SMT|Name=Termination
|RECORD=41|OwnerIndex=1517|IndexInSheet=18|OwnerPartId=-1|Location.X=209|Location.Y=962|Color=8388608|FontID=1|IsHidden=T|Text=0.049inch|Name=Width
|RECORD=41|OwnerIndex=1517|IndexInSheet=19|OwnerPartId=-1|Location.X=209|Location.Y=962|Color=8388608|FontID=1|IsHidden=T|Text=85°C|Name=Max Operating Temperature
|RECORD=41|OwnerIndex=1517|IndexInSheet=20|OwnerPartId=-1|Location.X=209|Location.Y=962|Color=8388608|FontID=1|IsHidden=T|Text=0.079inch|Name=Length
|RECORD=41|OwnerIndex=1517|IndexInSheet=21|OwnerPartId=-1|Location.X=209|Location.Y=962|Color=8388608|FontID=1|IsHidden=T|Text=0805|Name=Case/Package
|RECORD=41|OwnerIndex=1517|IndexInSheet=22|OwnerPartId=-1|Location.X=209|Location.Y=962|Color=8388608|FontID=1|IsHidden=T|Text=25V|Name=Voltage Rating
|RECORD=41|OwnerIndex=1517|IndexInSheet=23|OwnerPartId=-1|Location.X=209|Location.Y=962|Color=8388608|FontID=1|IsHidden=T|Text=-55°C|Name=Min Operating Temperature
|RECORD=41|OwnerIndex=1517|IndexInSheet=24|OwnerPartId=-1|Location.X=209|Location.Y=962|Color=8388608|FontID=1|IsHidden=T|Text=10%|Name=Tolerance
|RECORD=41|OwnerIndex=1517|IndexInSheet=25|OwnerPartId=-1|Location.X=209|Location.Y=962|Color=8388608|FontID=1|IsHidden=T|Text=X7R|Name=Dielectric
|RECORD=41|OwnerIndex=1517|IndexInSheet=26|OwnerPartId=-1|Location.X=209|Location.Y=962|Color=8388608|FontID=1|IsHidden=T|Text=2012|Name=Case Code (Metric)
|RECORD=41|OwnerIndex=1517|IndexInSheet=27|OwnerPartId=-1|Location.X=209|Location.Y=962|Color=8388608|FontID=1|IsHidden=T|Text=0805|Name=Case Code (Imperial)
|RECORD=41|OwnerIndex=1517|IndexInSheet=28|OwnerPartId=-1|Location.X=209|Location.Y=962|Color=8388608|FontID=1|IsHidden=T|Text=1.25mm|Name=Height
|RECORD=41|OwnerIndex=1517|IndexInSheet=29|OwnerPartId=-1|Location.X=209|Location.Y=962|Color=8388608|FontID=1|IsHidden=T|Text=16V|Name=Voltage
|RECORD=41|OwnerIndex=1517|IndexInSheet=30|OwnerPartId=-1|Location.X=209|Location.Y=962|Color=8388608|FontID=1|IsHidden=T|Text=M|Name=Series
|RECORD=34|OwnerIndex=1517|IndexInSheet=-1|OwnerPartId=-1|Location.X=231|Location.Y=947|Color=8388608|FontID=1|Text=C42|Name=Designator|ReadOnlyState=1
|RECORD=41|OwnerIndex=1517|IndexInSheet=-1|OwnerPartId=1|Location.X=231|Location.Y=937|Color=8388608|FontID=1|Text=10uF|Name=Comment
|RECORD=44|OwnerIndex=1517
|RECORD=45|OwnerIndex=1553|IndexInSheet=-1|UseComponentLibrary=T|ModelName=FP-MK212BG-MFG|ModelType=PCBLIB|DatafileCount=1|ModelDatafileEntity0=FP-MK212BG-MFG|ModelDatafileKind0=PCBLib|IsCurrent=T|DatalinksLocked=T|DatabaseDatalinksLocked=T
|RECORD=46|OwnerIndex=1554
|RECORD=48|OwnerIndex=1554
|RECORD=45|OwnerIndex=1553|IndexInSheet=-1|UseComponentLibrary=T|ModelName=FP-MK212BG-IPC_C|ModelType=PCBLIB|DatafileCount=1|ModelDatafileEntity0=FP-MK212BG-IPC_C|ModelDatafileKind0=PCBLib|DatalinksLocked=T|DatabaseDatalinksLocked=T
|RECORD=46|OwnerIndex=1557
|RECORD=48|OwnerIndex=1557
|RECORD=45|OwnerIndex=1553|IndexInSheet=-1|UseComponentLibrary=T|ModelName=FP-MK212BG-IPC_B|ModelType=PCBLIB|DatafileCount=1|ModelDatafileEntity0=FP-MK212BG-IPC_B|ModelDatafileKind0=PCBLib|DatalinksLocked=T|DatabaseDatalinksLocked=T
|RECORD=46|OwnerIndex=1560
|RECORD=48|OwnerIndex=1560
|RECORD=45|OwnerIndex=1553|IndexInSheet=-1|UseComponentLibrary=T|ModelName=FP-MK212BG-IPC_A|ModelType=PCBLIB|DatafileCount=1|ModelDatafileEntity0=FP-MK212BG-IPC_A|ModelDatafileKind0=PCBLib|DatalinksLocked=T|DatabaseDatalinksLocked=T
|RECORD=46|OwnerIndex=1563
|RECORD=48|OwnerIndex=1563
|RECORD=45|OwnerIndex=1553|IndexInSheet=-1|UseComponentLibrary=T|ModelName=TMK212BBJ106_G-T|ModelType=SIM|IsCurrent=T|DatalinksLocked=T|DatabaseDatalinksLocked=T
|RECORD=46|OwnerIndex=1566
|RECORD=48|OwnerIndex=1566
|RECORD=41|OwnerIndex=1568|IndexInSheet=-1|OwnerPartId=-1|Color=8388608|FontID=1|IsHidden=T|Text=General|Name=Kind
|RECORD=41|OwnerIndex=1568|IndexInSheet=-1|OwnerPartId=-1|Color=8388608|FontID=1|IsHidden=T|Text=Spice Subcircuit|Name=SubKind
|RECORD=41|OwnerIndex=1568|IndexInSheet=-1|OwnerPartId=-1|Color=8388608|FontID=1|IsHidden=T|Name=Spice Prefix
|RECORD=41|OwnerIndex=1568|IndexInSheet=-1|OwnerPartId=-1|Color=8388608|FontID=1|IsHidden=T|Name=Excluded Parts
|RECORD=41|OwnerIndex=1568|IndexInSheet=-1|OwnerPartId=-1|Color=8388608|FontID=1|IsHidden=T|Name=Netlist
|RECORD=17|IndexInSheet=157|OwnerPartId=-1|ShowNetName=T|Location.X=410|Location.Y=960|Orientation=2|Color=255|FontID=1|Text=RCB_GPS1_PIN11|IsCrossSheetConnector=T
|RECORD=17|IndexInSheet=158|OwnerPartId=-1|ShowNetName=T|Location.X=410|Location.Y=950|Orientation=2|Color=255|FontID=1|Text=RCB_GPS1_PIN12|IsCrossSheetConnector=T
|RECORD=17|IndexInSheet=159|OwnerPartId=-1|ShowNetName=T|Location.X=810|Location.Y=980|Color=255|FontID=1|Text=GPS1_PIN13|IsCrossSheetConnector=T
|RECORD=17|IndexInSheet=160|OwnerPartId=-1|ShowNetName=T|Location.X=810|Location.Y=970|Color=255|FontID=1|Text=GPS1_PIN14|IsCrossSheetConnector=T
|RECORD=17|IndexInSheet=161|OwnerPartId=-1|ShowNetName=T|Location.X=810|Location.Y=960|Color=255|FontID=1|Text=GPS1_PIN15|IsCrossSheetConnector=T
|RECORD=17|IndexInSheet=162|OwnerPartId=-1|ShowNetName=T|Location.X=370|Location.Y=450|Orientation=2|Color=255|FontID=1|Text=RCB_GPS2_PIN11|IsCrossSheetConnector=T
|RECORD=17|IndexInSheet=163|OwnerPartId=-1|ShowNetName=T|Location.X=370|Location.Y=440|Orientation=2|Color=255|FontID=1|Text=RCB_GPS2_PIN12|IsCrossSheetConnector=T
|RECORD=17|IndexInSheet=164|OwnerPartId=-1|ShowNetName=T|Location.X=640|Location.Y=470|Color=255|FontID=1|Text=GPS2_PIN13|IsCrossSheetConnector=T
|RECORD=17|IndexInSheet=165|OwnerPartId=-1|ShowNetName=T|Location.X=640|Location.Y=460|Color=255|FontID=1|Text=GPS2_PIN14|IsCrossSheetConnector=T
|RECORD=17|IndexInSheet=166|OwnerPartId=-1|ShowNetName=T|Location.X=640|Location.Y=450|Color=255|FontID=1|Text=GPS2_PIN15|IsCrossSheetConnector=T
|RECORD=1|LibReference=ba837af00a0b6167256f888b31462b1|ComponentDescription=IMU ACCEL/GYRO/MAG I2C 28LGA|PartCount=2|DisplayModeCount=1|IndexInSheet=167|OwnerPartId=-1|Location.X=1300|Location.Y=400|CurrentPartId=1|LibraryPath=*|SourceLibraryName=Altium Content Vault|TargetFileName=*|AreaColor=11599871|Color=128|PartIDLocked=T|DesignItemId=CMP-2000-05075-4|AllPinCount=28
|RECORD=14|OwnerIndex=1584|IsNotAccesible=T|OwnerPartId=1|Location.X=1320|Location.Y=180|Corner.X=1470|Corner.Y=410|LineWidth=1|Color=128|AreaColor=11599871|IsSolid=T
|RECORD=2|OwnerIndex=1584|OwnerPartId=1|Electrical=7|PinConglomerate=58|PinLength=20|Location.X=1320|Location.Y=400|Name=VDD|Designator=3|PinPropagationDelay=0.000000E+000
|RECORD=2|OwnerIndex=1584|OwnerPartId=1|Electrical=7|PinConglomerate=58|PinLength=20|Location.X=1320|Location.Y=390|Name=VDDIO|Designator=28|PinPropagationDelay=0.000000E+000
|RECORD=2|OwnerIndex=1584|OwnerPartId=1|Electrical=4|PinConglomerate=58|PinLength=20|Location.X=1320|Location.Y=370|Name=NC|Designator=1|PinPropagationDelay=0.000000E+000
|RECORD=2|OwnerIndex=1584|OwnerPartId=1|Electrical=1|PinConglomerate=58|PinLength=20|Location.X=1320|Location.Y=280|Name=SWDIO|Designator=7|PinPropagationDelay=0.000000E+000
|RECORD=2|OwnerIndex=1584|OwnerPartId=1|SymBol_InnerEdge=3|PinConglomerate=58|PinLength=20|Location.X=1320|Location.Y=270|Name=SWCLK|Designator=8|PinPropagationDelay=0.000000E+000
|RECORD=2|OwnerIndex=1584|OwnerPartId=1|Electrical=2|PinConglomerate=56|PinLength=20|Location.X=1470|Location.Y=270|Name=BL IND|Designator=10|PinPropagationDelay=0.000000E+000
|RECORD=2|OwnerIndex=1584|OwnerPartId=1|Electrical=4|PinConglomerate=58|PinLength=20|Location.X=1320|Location.Y=240|Name=NC|Designator=12|PinPropagationDelay=0.000000E+000
|RECORD=2|OwnerIndex=1584|OwnerPartId=1|Electrical=4|PinConglomerate=58|PinLength=20|Location.X=1320|Location.Y=230|Name=NC|Designator=13|PinPropagationDelay=0.000000E+000
|RECORD=2|OwnerIndex=1584|OwnerPartId=1|Electrical=4|PinConglomerate=56|PinLength=20|Location.X=1470|Location.Y=250|Name=NC|Designator=15|PinPropagationDelay=0.000000E+000
|RECORD=2|OwnerIndex=1584|OwnerPartId=1|Electrical=4|PinConglomerate=56|PinLength=20|Location.X=1470|Location.Y=240|Name=NC|Designator=16|PinPropagationDelay=0.000000E+000
|RECORD=2|OwnerIndex=1584|OwnerPartId=1|Electrical=4|PinConglomerate=56|PinLength=20|Location.X=1470|Location.Y=220|Name=NC|Designator=21|PinPropagationDelay=0.000000E+000
|RECORD=2|OwnerIndex=1584|OwnerPartId=1|Electrical=4|PinConglomerate=56|PinLength=20|Location.X=1470|Location.Y=230|Name=NC|Designator=22|PinPropagationDelay=0.000000E+000
|RECORD=2|OwnerIndex=1584|OwnerPartId=1|Electrical=4|PinConglomerate=58|PinLength=20|Location.X=1320|Location.Y=220|Name=NC|Designator=23|PinPropagationDelay=0.000000E+000
|RECORD=2|OwnerIndex=1584|OwnerPartId=1|Electrical=4|PinConglomerate=58|PinLength=20|Location.X=1320|Location.Y=210|Name=NC|Designator=24|PinPropagationDelay=0.000000E+000
|RECORD=2|OwnerIndex=1584|OwnerPartId=1|PinConglomerate=58|PinLength=20|Location.X=1320|Location.Y=310|Name=PS0|Designator=6|PinPropagationDelay=0.000000E+000
|RECORD=2|OwnerIndex=1584|OwnerPartId=1|PinConglomerate=58|PinLength=20|Location.X=1320|Location.Y=300|Name=PS1|Designator=5|PinPropagationDelay=0.000000E+000
|RECORD=2|OwnerIndex=1584|OwnerPartId=1|PinConglomerate=56|PinLength=20|Location.X=1470|Location.Y=400|Name=B\O\O\T\ \L\O\A\D\ \P\I\N\|Designator=4|PinPropagationDelay=0.000000E+000
|RECORD=2|OwnerIndex=1584|OwnerPartId=1|PinConglomerate=58|PinLength=20|Location.X=1320|Location.Y=350|Name=R\E\S\E\T\|Designator=11|PinPropagationDelay=0.000000E+000
|RECORD=2|OwnerIndex=1584|OwnerPartId=1|Electrical=4|PinConglomerate=56|PinLength=20|Location.X=1470|Location.Y=380|Name=CAP|Designator=9|PinPropagationDelay=0.000000E+000
|RECORD=2|OwnerIndex=1584|OwnerPartId=1|Electrical=4|PinConglomerate=56|PinLength=20|Location.X=1470|Location.Y=360|Name=INT|Designator=14|PinPropagationDelay=0.000000E+000
|RECORD=2|OwnerIndex=1584|OwnerPartId=1|PinConglomerate=58|PinLength=20|Location.X=1320|Location.Y=330|Name=XIN32|Designator=27|PinPropagationDelay=0.000000E+000
|RECORD=2|OwnerIndex=1584|OwnerPartId=1|Electrical=4|PinConglomerate=56|PinLength=20|Location.X=1470|Location.Y=340|Name=XOUT32|Designator=26|PinPropagationDelay=0.000000E+000
|RECORD=2|OwnerIndex=1584|OwnerPartId=1|Electrical=1|PinConglomerate=56|PinLength=20|Location.X=1470|Location.Y=320|Name=COM0|Designator=20|PinPropagationDelay=0.000000E+000
|RECORD=2|OwnerIndex=1584|OwnerPartId=1|Electrical=1|PinConglomerate=56|PinLength=20|Location.X=1470|Location.Y=310|Name=COM1|Designator=19|PinPropagationDelay=0.000000E+000
|RECORD=2|OwnerIndex=1584|OwnerPartId=1|Electrical=1|PinConglomerate=56|PinLength=20|Location.X=1470|Location.Y=300|Name=COM2|Designator=18|PinPropagationDelay=0.000000E+000
|RECORD=2|OwnerIndex=1584|OwnerPartId=1|PinConglomerate=56|PinLength=20|Location.X=1470|Location.Y=290|Name=COM3|Designator=17|PinPropagationDelay=0.000000E+000
|RECORD=2|OwnerIndex=1584|OwnerPartId=1|Electrical=7|PinConglomerate=56|PinLength=20|Location.X=1470|Location.Y=200|Name=GND|Designator=2|PinPropagationDelay=0.000000E+000
|RECORD=2|OwnerIndex=1584|OwnerPartId=1|Electrical=7|PinConglomerate=56|PinLength=20|Location.X=1470|Location.Y=190|Name=GNDIO|Designator=25|PinPropagationDelay=0.000000E+000
|RECORD=41|OwnerIndex=1584|IndexInSheet=29|OwnerPartId=-1|Location.X=1298|Location.Y=410|Color=8388608|FontID=1|IsHidden=T|Text=Tape and Reel|Name=Packaging
|RECORD=41|OwnerIndex=1584|IndexInSheet=30|OwnerPartId=-1|Location.X=1298|Location.Y=410|Color=8388608|FontID=1|IsHidden=T|Text=LGA|Name=Case/Package
|RECORD=41|OwnerIndex=1584|IndexInSheet=31|OwnerPartId=-1|Location.X=1298|Location.Y=410|Color=8388608|FontID=1|IsHidden=T|Text=-40°C|Name=Min Operating Temperature
|RECORD=41|OwnerIndex=1584|IndexInSheet=32|OwnerPartId=-1|Location.X=1298|Location.Y=410|Color=8388608|FontID=1|IsHidden=T|Text=Surface Mount|Name=Mount
|RECORD=41|OwnerIndex=1584|IndexInSheet=33|OwnerPartId=-1|Location.X=1298|Location.Y=410|Color=8388608|FontID=1|IsHidden=T|Text=Accelerometer|Name=Sensor Type
|RECORD=41|OwnerIndex=1584|IndexInSheet=34|OwnerPartId=-1|Location.X=1298|Location.Y=410|Color=8388608|FontID=1|IsHidden=T|Text=I2C|Name=Output Type
|RECORD=41|OwnerIndex=1584|IndexInSheet=35|OwnerPartId=-1|Location.X=1298|Location.Y=410|Color=8388608|FontID=1|IsHidden=T|Text=Lead Free|Name=Lead Free
|RECORD=41|OwnerIndex=1584|IndexInSheet=36|OwnerPartId=-1|Location.X=1298|Location.Y=410|Color=8388608|FontID=1|IsHidden=T|Text=85°C|Name=Max Operating Temperature
|RECORD=34|OwnerIndex=1584|IndexInSheet=-1|OwnerPartId=-1|Location.X=1320|Location.Y=410|Color=8388608|FontID=1|Text=U13|Name=Designator|ReadOnlyState=1
|RECORD=41|OwnerIndex=1584|IndexInSheet=-1|OwnerPartId=1|Location.X=1320|Location.Y=170|Color=8388608|FontID=1|Text=BNO055|Name=Comment
|RECORD=44|OwnerIndex=1584
|RECORD=45|OwnerIndex=1652|IndexInSheet=-1|UseComponentLibrary=T|ModelName=FP-BNO055-MFG|ModelType=PCBLIB|DatafileCount=1|ModelDatafileEntity0=FP-BNO055-MFG|ModelDatafileKind0=PCBLib|IsCurrent=T|DatalinksLocked=T|DatabaseDatalinksLocked=T
|RECORD=46|OwnerIndex=1653
|RECORD=48|OwnerIndex=1653
|RECORD=17|IndexInSheet=168|OwnerPartId=-1|Style=4|ShowNetName=T|Location.X=1510|Location.Y=170|Orientation=3|Color=128|FontID=1|Text=GND
|RECORD=17|IndexInSheet=169|OwnerPartId=-1|ShowNetName=T|Location.X=1100|Location.Y=440|Orientation=1|Color=128|FontID=1|Text=BNO_P3V3
|RECORD=17|IndexInSheet=170|OwnerPartId=-1|ShowNetName=T|Location.X=1160|Location.Y=440|Orientation=1|Color=128|FontID=1|Text=BNO_P3V3
|RECORD=17|IndexInSheet=171|OwnerPartId=-1|Style=4|ShowNetName=T|Location.X=1120|Location.Y=240|Orientation=3|Color=128|FontID=1|Text=GND
|RECORD=17|IndexInSheet=172|OwnerPartId=-1|Style=4|ShowNetName=T|Location.X=1160|Location.Y=240|Orientation=3|Color=128|FontID=1|Text=GND
|RECORD=17|IndexInSheet=173|OwnerPartId=-1|ShowNetName=T|Location.X=1640|Location.Y=470|Orientation=1|Color=128|FontID=1|Text=BNO_P3V3
|RECORD=17|IndexInSheet=174|OwnerPartId=-1|Style=4|ShowNetName=T|Location.X=1640|Location.Y=210|Orientation=3|Color=128|FontID=1|Text=GND
|RECORD=17|IndexInSheet=175|OwnerPartId=-1|Style=4|ShowNetName=T|Location.X=1600|Location.Y=210|Orientation=3|Color=128|FontID=1|Text=GND
|RECORD=17|IndexInSheet=176|OwnerPartId=-1|ShowNetName=T|Location.X=1560|Location.Y=310|Color=255|FontID=1|Text=SENS_I2C_SCL|IsCrossSheetConnector=T
|RECORD=17|IndexInSheet=177|OwnerPartId=-1|ShowNetName=T|Location.X=1560|Location.Y=320|Color=255|FontID=1|Text=SENS_I2C_SDA|IsCrossSheetConnector=T
|RECORD=17|IndexInSheet=178|OwnerPartId=-1|ShowNetName=T|Location.X=1170|Location.Y=170|Orientation=1|Color=128|FontID=1|Text=BNO_P3V3
|RECORD=17|IndexInSheet=179|OwnerPartId=-1|ShowNetName=T|Location.X=1110|Location.Y=340|Orientation=2|Color=255|FontID=1|Text=PCIE_PERST|IsCrossSheetConnector=T
|RECORD=1|LibReference=RES-2|ComponentDescription=Chip Resistor, 0 Ohm, 0.1 W, -55 to 155 degC, 0402 (1005 Metric), RoHS, Tape and Reel|PartCount=2|DisplayModeCount=1|IndexInSheet=180|OwnerPartId=-1|Location.X=1220|Location.Y=340|CurrentPartId=1|LibraryPath=*|SourceLibraryName=Altium Content Vault|TargetFileName=*|AreaColor=11599871|Color=128|PartIDLocked=T|DesignItemId=CMP-2000-07451-1|AllPinCount=2
|RECORD=2|OwnerIndex=1668|OwnerPartId=1|FormalType=1|Electrical=4|PinConglomerate=32|PinLength=10|Location.X=1240|Location.Y=340|Name=2|Designator=2|PinPropagationDelay=0.000000E+000
|RECORD=2|OwnerIndex=1668|OwnerPartId=1|FormalType=1|Electrical=4|PinConglomerate=34|PinLength=10|Location.X=1220|Location.Y=340|Name=1|Designator=1|PinPropagationDelay=0.000000E+000
|RECORD=6|OwnerIndex=1668|IsNotAccesible=T|IndexInSheet=2|OwnerPartId=1|LineWidth=1|Color=16711680|LocationCount=10|X1=1240|Y1=340|X2=1236|Y2=340|X3=1235|Y3=338|X4=1233|Y4=342|X5=1231|Y5=338|X6=1229|Y6=342|X7=1227|Y7=338|X8=1225|Y8=342|X9=1224|Y9=340|X10=1220|Y10=340
|RECORD=41|OwnerIndex=1668|IndexInSheet=3|OwnerPartId=-1|Location.X=1208|Location.Y=355|Color=8388608|FontID=1|IsHidden=T|Text=50V|Name=Voltage Rating (DC)
|RECORD=41|OwnerIndex=1668|IndexInSheet=4|OwnerPartId=-1|Location.X=1208|Location.Y=355|Color=8388608|FontID=1|IsHidden=T|Text=2|Name=Number of Terminations
|RECORD=41|OwnerIndex=1668|IndexInSheet=5|OwnerPartId=-1|Location.X=1208|Location.Y=355|Color=8388608|FontID=1|IsHidden=T|Text=SurfaceMount|Name=Mount
|RECORD=41|OwnerIndex=1668|IndexInSheet=6|OwnerPartId=-1|Location.X=1208|Location.Y=355|Color=8388608|FontID=1|IsHidden=T|Text=0.35mm|Name=Height
|RECORD=41|OwnerIndex=1668|IndexInSheet=7|OwnerPartId=-1|Location.X=1208|Location.Y=355|Color=8388608|FontID=1|IsHidden=T|Text=TapeandReel|Name=Packaging
|RECORD=41|OwnerIndex=1668|IndexInSheet=8|OwnerPartId=-1|Location.X=1208|Location.Y=355|Color=8388608|FontID=1|IsHidden=T|Text=Tin|Name=Contact Plating
|RECORD=41|OwnerIndex=1668|IndexInSheet=9|OwnerPartId=-1|Location.X=1208|Location.Y=355|Color=8388608|FontID=3|IsHidden=T|Text=http://www.panasonic.com/|Name=Manufacturer URL
|RECORD=41|OwnerIndex=1668|IndexInSheet=10|OwnerPartId=-1|Location.X=1208|Location.Y=355|Color=8388608|FontID=1|IsHidden=T|Text=ThickFilm|Name=Composition
|RECORD=41|OwnerIndex=1668|IndexInSheet=11|OwnerPartId=-1|Location.X=1208|Location.Y=355|Color=8388608|FontID=1|IsHidden=T|Text=155degC|Name=Max Operating Temperature
|RECORD=41|OwnerIndex=1668|IndexInSheet=12|OwnerPartId=-1|Location.X=1208|Location.Y=355|Color=8388608|FontID=1|IsHidden=T|Text=600ppm/??C|Name=Temperature Coefficient
|RECORD=41|OwnerIndex=1668|IndexInSheet=13|OwnerPartId=-1|Location.X=1208|Location.Y=355|Color=8388608|FontID=1|IsHidden=T|Text=NoSVHC|Name=REACH SVHC
|RECORD=41|OwnerIndex=1668|IndexInSheet=14|OwnerPartId=-1|Location.X=1208|Location.Y=355|Color=8388608|FontID=1|IsHidden=T|Text=0402|Name=Case/Package
|RECORD=41|OwnerIndex=1668|IndexInSheet=15|OwnerPartId=-1|Location.X=1208|Location.Y=355|Color=8388608|FontID=1|IsHidden=T|Text=100mW|Name=Max Power Dissipation
|RECORD=41|OwnerIndex=1668|IndexInSheet=16|OwnerPartId=-1|Location.X=1208|Location.Y=355|Color=8388608|FontID=1|IsHidden=T|Text=402|Name=Package Reference
|RECORD=41|OwnerIndex=1668|IndexInSheet=17|OwnerPartId=-1|Location.X=1208|Location.Y=355|Color=8388608|FontID=1|IsHidden=T|Text=0.5mm|Name=Depth
|RECORD=41|OwnerIndex=1668|IndexInSheet=18|OwnerPartId=-1|Location.X=1208|Location.Y=355|Color=8388608|FontID=1|IsHidden=T|Text=Panasonic|Name=Manufacturer
|RECORD=41|OwnerIndex=1668|IndexInSheet=19|OwnerPartId=-1|Location.X=1208|Location.Y=355|Color=8388608|FontID=1|IsHidden=T|Text=2-Pin Surface Mount Device, Body 1 x 0.5 mm|Name=Package Description
|RECORD=41|OwnerIndex=1668|IndexInSheet=20|OwnerPartId=-1|Location.X=1208|Location.Y=355|Color=8388608|FontID=3|IsHidden=T|Text=https://industrial.panasonic.com/cdbs/www-data/pdf/RDA0000/AOA0000C301.pdf|Name=Datasheet URL
|RECORD=41|OwnerIndex=1668|IndexInSheet=21|OwnerPartId=-1|Location.X=1208|Location.Y=355|Color=8388608|FontID=1|IsHidden=T|Text=True|Name=RoHSCompliant
|RECORD=41|OwnerIndex=1668|IndexInSheet=22|OwnerPartId=-1|Location.X=1208|Location.Y=355|Color=8388608|FontID=1|IsHidden=T|Text=0402|Name=Case Code (Imperial)
|RECORD=41|OwnerIndex=1668|IndexInSheet=23|OwnerPartId=-1|Location.X=1208|Location.Y=355|Color=8388608|FontID=1|IsHidden=T|Text=0mOhm|Name=Resistance
|RECORD=41|OwnerIndex=1668|IndexInSheet=24|OwnerPartId=-1|Location.X=1208|Location.Y=355|Color=8388608|FontID=1|IsHidden=T|Text=Not|Name=Military Standard
|RECORD=41|OwnerIndex=1668|IndexInSheet=25|OwnerPartId=-1|Location.X=1208|Location.Y=355|Color=8388608|FontID=1|IsHidden=T|Text=5%|Name=Tolerance
|RECORD=41|OwnerIndex=1668|IndexInSheet=26|OwnerPartId=-1|Location.X=1208|Location.Y=355|Color=8388608|FontID=1|IsHidden=T|Text=-55degC|Name=Min Operating Temperature
|RECORD=41|OwnerIndex=1668|IndexInSheet=27|OwnerPartId=-1|Location.X=1208|Location.Y=355|Color=8388608|FontID=1|IsHidden=T|Text=100mW|Name=Power Rating
|RECORD=41|OwnerIndex=1668|IndexInSheet=28|OwnerPartId=-1|Location.X=1208|Location.Y=355|Color=8388608|FontID=1|IsHidden=T|Text=03/2015|Name=Datasheet Version
|RECORD=41|OwnerIndex=1668|IndexInSheet=29|OwnerPartId=-1|Location.X=1208|Location.Y=355|Color=8388608|FontID=1|IsHidden=T|Text=1mm|Name=Length
|RECORD=41|OwnerIndex=1668|IndexInSheet=30|OwnerPartId=-1|Location.X=1208|Location.Y=355|Color=8388608|FontID=1|IsHidden=T|Text=1005|Name=Case Code (Metric)
|RECORD=41|OwnerIndex=1668|IndexInSheet=31|OwnerPartId=-1|Location.X=1208|Location.Y=355|Color=8388608|FontID=1|IsHidden=T|Text=SMD/SMT|Name=Termination
|RECORD=41|OwnerIndex=1668|IndexInSheet=32|OwnerPartId=-1|Location.X=1208|Location.Y=355|Color=8388608|FontID=1|IsHidden=T|Text=SurfaceMount|Name=Mounting Technology
|RECORD=41|OwnerIndex=1668|IndexInSheet=33|OwnerPartId=-1|Location.X=1208|Location.Y=355|Color=8388608|FontID=1|IsHidden=T|Text=50V|Name=Voltage Rating
|RECORD=41|OwnerIndex=1668|IndexInSheet=34|OwnerPartId=-1|Location.X=1208|Location.Y=355|Color=8388608|FontID=1|IsHidden=T|Text=0.02inch|Name=Width
|RECORD=41|OwnerIndex=1668|IndexInSheet=35|OwnerPartId=-1|Location.X=1208|Location.Y=355|Color=8388608|FontID=1|IsHidden=T|Text=1|Name=Package Quantity
|RECORD=41|OwnerIndex=1668|IndexInSheet=36|OwnerPartId=-1|Location.X=1208|Location.Y=355|Color=8388608|FontID=1|IsHidden=T|Text=LeadFree|Name=Lead Free
|RECORD=41|OwnerIndex=1668|IndexInSheet=37|OwnerPartId=-1|Location.X=1208|Location.Y=355|Color=8388608|FontID=1|IsHidden=T|Text=No|Name=Radiation Hardening
|RECORD=34|OwnerIndex=1668|IndexInSheet=-1|OwnerPartId=-1|Location.X=1200|Location.Y=340|Color=8388608|FontID=1|Text=R54|Name=Designator|ReadOnlyState=1
|RECORD=41|OwnerIndex=1668|IndexInSheet=-1|OwnerPartId=-1|Location.X=1240|Location.Y=340|Color=8388608|FontID=1|Text=0_1%_0402|Name=Comment
|RECORD=44|OwnerIndex=1668
|RECORD=45|OwnerIndex=1711|IndexInSheet=-1|Description=Chip Resistor, 2-Leads, Body 1.05x0.55mm, IPC High Density|UseComponentLibrary=T|ModelName=RESC1005X40X25LL05T05|ModelType=PCBLIB|DatafileCount=1|ModelDatafileEntity0=RESC1005X40X25LL05T05|ModelDatafileKind0=PCBLib|IsCurrent=T|DatalinksLocked=T|DatabaseDatalinksLocked=T
|RECORD=46|OwnerIndex=1712
|RECORD=48|OwnerIndex=1712
|RECORD=41|OwnerIndex=1714|IndexInSheet=-1|OwnerPartId=-1|Color=8388608|FontID=1|IsHidden=T|Text=2D|Name=Available Preview Images
|RECORD=45|OwnerIndex=1711|IndexInSheet=-1|Description=Chip Resistor, 2-Leads, Body 1.05x0.55mm, IPC Low Density|UseComponentLibrary=T|ModelName=RESC1005X40X25ML05T05|ModelType=PCBLIB|DatafileCount=1|ModelDatafileEntity0=RESC1005X40X25ML05T05|ModelDatafileKind0=PCBLib|DatalinksLocked=T|DatabaseDatalinksLocked=T
|RECORD=46|OwnerIndex=1716
|RECORD=48|OwnerIndex=1716
|RECORD=41|OwnerIndex=1718|IndexInSheet=-1|OwnerPartId=-1|Color=8388608|FontID=1|IsHidden=T|Text=2D|Name=Available Preview Images
|RECORD=45|OwnerIndex=1711|IndexInSheet=-1|Description=Chip Resistor, 2-Leads, Body 1.05x0.55mm, IPC Medium Density|UseComponentLibrary=T|ModelName=RESC1005X40X25NL05T05|ModelType=PCBLIB|DatafileCount=1|ModelDatafileEntity0=RESC1005X40X25NL05T05|ModelDatafileKind0=PCBLib|DatalinksLocked=T|DatabaseDatalinksLocked=T
|RECORD=46|OwnerIndex=1720
|RECORD=48|OwnerIndex=1720
|RECORD=41|OwnerIndex=1722|IndexInSheet=-1|OwnerPartId=-1|Color=8388608|FontID=1|IsHidden=T|Text=2D|Name=Available Preview Images
|RECORD=17|IndexInSheet=181|OwnerPartId=-1|ShowNetName=T|Location.X=1510|Location.Y=360|Color=255|FontID=1|Text=BNO_INT|IsCrossSheetConnector=T
|RECORD=17|IndexInSheet=182|OwnerPartId=-1|ShowNetName=T|Location.X=1530|Location.Y=460|Orientation=2|Color=255|FontID=1|Text=BNO_INT|IsCrossSheetConnector=T
|RECORD=17|IndexInSheet=183|OwnerPartId=-1|ShowNetName=T|Location.X=1570|Location.Y=270|Color=255|FontID=1|Text=BNO_BLIND|IsCrossSheetConnector=T
|RECORD=17|IndexInSheet=184|OwnerPartId=-1|ShowNetName=T|Location.X=1260|Location.Y=330|Orientation=2|Color=255|FontID=1|Text=BNO_XIN32|IsCrossSheetConnector=T
|RECORD=17|IndexInSheet=185|OwnerPartId=-1|ShowNetName=T|Location.X=1510|Location.Y=340|Color=255|FontID=1|Text=BNO_XOUT32|IsCrossSheetConnector=T
|RECORD=17|IndexInSheet=186|OwnerPartId=-1|ShowNetName=T|Location.X=1300|Location.Y=540|Orientation=2|Color=255|FontID=1|Text=BNO_XIN32|IsCrossSheetConnector=T
|RECORD=17|IndexInSheet=187|OwnerPartId=-1|ShowNetName=T|Location.X=1460|Location.Y=540|Color=255|FontID=1|Text=BNO_XOUT32|IsCrossSheetConnector=T
|RECORD=1|LibReference=RES-2|ComponentDescription=Chip Resistor, 4.7 KOhm, +/- 1%, 0.1 W, -55 to 155 degC, 0402 (1005 Metric), RoHS, Tape and Reel|PartCount=2|DisplayModeCount=1|IndexInSheet=188|OwnerPartId=-1|Location.X=1210|Location.Y=200|Orientation=1|CurrentPartId=1|LibraryPath=*|SourceLibraryName=Altium Content Vault|TargetFileName=*|AreaColor=11599871|Color=128|PartIDLocked=T|DesignItemId=CMP-2002-01154-4|AllPinCount=2
|RECORD=2|OwnerIndex=1731|OwnerPartId=1|FormalType=1|Electrical=4|PinConglomerate=33|PinLength=10|Location.X=1210|Location.Y=220|Name=2|Designator=2|PinPropagationDelay=0.000000E+000
|RECORD=2|OwnerIndex=1731|OwnerPartId=1|FormalType=1|Electrical=4|PinConglomerate=35|PinLength=10|Location.X=1210|Location.Y=200|Name=1|Designator=1|PinPropagationDelay=0.000000E+000
|RECORD=6|OwnerIndex=1731|IsNotAccesible=T|IndexInSheet=2|OwnerPartId=1|LineWidth=1|Color=16711680|LocationCount=10|X1=1210|Y1=220|X2=1210|Y2=216|X3=1212|Y3=215|X4=1208|Y4=213|X5=1212|Y5=211|X6=1208|Y6=209|X7=1212|Y7=207|X8=1208|Y8=205|X9=1210|Y9=204|X10=1210|Y10=200
|RECORD=41|OwnerIndex=1731|IndexInSheet=3|OwnerPartId=-1|Location.X=1207|Location.Y=232|Color=8388608|FontID=1|IsHidden=T|Text=0.35 mm|Name=Height
|RECORD=41|OwnerIndex=1731|IndexInSheet=4|OwnerPartId=-1|Location.X=1207|Location.Y=232|Color=8388608|FontID=1|IsHidden=T|Text=Surface Mount|Name=Mounting Technology
|RECORD=41|OwnerIndex=1731|IndexInSheet=5|OwnerPartId=-1|Location.X=1207|Location.Y=232|Color=8388608|FontID=1|IsHidden=T|Text=Yes|Name=REACH SVHC
|RECORD=41|OwnerIndex=1731|IndexInSheet=6|OwnerPartId=-1|Location.X=1207|Location.Y=232|Color=8388608|FontID=1|IsHidden=T|Text=4.7 KOhm|Name=Resistance
|RECORD=41|OwnerIndex=1731|IndexInSheet=7|OwnerPartId=-1|Location.X=1207|Location.Y=232|Color=8388608|FontID=1|IsHidden=T|Text=155 degC|Name=Max Operating Temperature
|RECORD=41|OwnerIndex=1731|IndexInSheet=8|OwnerPartId=-1|Location.X=1207|Location.Y=232|Color=8388608|FontID=1|IsHidden=T|Text=Manufacturer URL|Name=ComponentLink1Description
|RECORD=41|OwnerIndex=1731|IndexInSheet=9|OwnerPartId=-1|Location.X=1207|Location.Y=232|Color=8388608|FontID=1|IsHidden=T|Text=Datasheet|Name=ComponentLink2Description
|RECORD=41|OwnerIndex=1731|IndexInSheet=10|OwnerPartId=-1|Location.X=1207|Location.Y=232|Color=8388608|FontID=1|IsHidden=T|Text=2|Name=Pins
|RECORD=41|OwnerIndex=1731|IndexInSheet=11|OwnerPartId=-1|Location.X=1207|Location.Y=232|Color=8388608|FontID=1|IsHidden=T|Text=0402|Name=PackageReference
|RECORD=41|OwnerIndex=1731|IndexInSheet=12|OwnerPartId=-1|Location.X=1207|Location.Y=232|Color=8388608|FontID=1|IsHidden=T|Text=1%|Name=Tolerance
|RECORD=41|OwnerIndex=1731|IndexInSheet=13|OwnerPartId=-1|Location.X=1207|Location.Y=232|Color=8388608|FontID=1|IsHidden=T|Text=0402|Name=Case Code (Imperial)
|RECORD=41|OwnerIndex=1731|IndexInSheet=14|OwnerPartId=-1|Location.X=1207|Location.Y=232|Color=8388608|FontID=1|IsHidden=T|Text=1 mm|Name=Length
|RECORD=41|OwnerIndex=1731|IndexInSheet=15|OwnerPartId=-1|Location.X=1207|Location.Y=232|Color=8388608|FontID=1|IsHidden=T|Text=2-Pin Surface Mount Device, Body 1 x 0.5 mm|Name=PackageDescription
|RECORD=41|OwnerIndex=1731|IndexInSheet=16|OwnerPartId=-1|Location.X=1207|Location.Y=232|Color=8388608|FontID=1|IsHidden=T|Text=ERJ-2RKF4701X|Name=PartNumber
|RECORD=41|OwnerIndex=1731|IndexInSheet=17|OwnerPartId=-1|Location.X=1207|Location.Y=232|Color=8388608|FontID=1|IsHidden=T|Text=true|Name=RoHSCompliant
|RECORD=41|OwnerIndex=1731|IndexInSheet=18|OwnerPartId=-1|Location.X=1207|Location.Y=232|Color=8388608|FontID=1|IsHidden=T|Text=1|Name=Package Quantity
|RECORD=41|OwnerIndex=1731|IndexInSheet=19|OwnerPartId=-1|Location.X=1207|Location.Y=232|Color=8388608|FontID=1|IsHidden=T|Text=No|Name=Radiation Hardening
|RECORD=41|OwnerIndex=1731|IndexInSheet=20|OwnerPartId=-1|Location.X=1207|Location.Y=232|Color=8388608|FontID=1|IsHidden=T|Text=04/2015|Name=DatasheetVersion
|RECORD=41|OwnerIndex=1731|IndexInSheet=21|OwnerPartId=-1|Location.X=1207|Location.Y=232|Color=8388608|FontID=1|IsHidden=T|Text=0.5 mm|Name=Width
|RECORD=41|OwnerIndex=1731|IndexInSheet=22|OwnerPartId=-1|Location.X=1207|Location.Y=232|Color=8388608|FontID=1|IsHidden=T|Text=1005|Name=Case Code (Metric)
|RECORD=41|OwnerIndex=1731|IndexInSheet=23|OwnerPartId=-1|Location.X=1207|Location.Y=232|Color=8388608|FontID=1|IsHidden=T|Text=50 V|Name=Voltage Rating
|RECORD=41|OwnerIndex=1731|IndexInSheet=24|OwnerPartId=-1|Location.X=1207|Location.Y=232|Color=8388608|FontID=1|IsHidden=T|Text=0402|Name=Case\/Package
|RECORD=41|OwnerIndex=1731|IndexInSheet=25|OwnerPartId=-1|Location.X=1207|Location.Y=232|Color=8388608|FontID=1|IsHidden=T|Text=Surface Mount|Name=Mount
|RECORD=41|OwnerIndex=1731|IndexInSheet=26|OwnerPartId=-1|Location.X=1207|Location.Y=232|Color=8388608|FontID=3|IsHidden=T|Text=http://www.panasonic.com/|Name=ComponentLink1URL
|RECORD=41|OwnerIndex=1731|IndexInSheet=27|OwnerPartId=-1|Location.X=1207|Location.Y=232|Color=8388608|FontID=1|IsHidden=T|Text=-55 degC|Name=Min Operating Temperature
|RECORD=41|OwnerIndex=1731|IndexInSheet=28|OwnerPartId=-1|Location.X=1207|Location.Y=232|Color=8388608|FontID=1|IsHidden=T|Text=100 mW|Name=Power Rating
|RECORD=41|OwnerIndex=1731|IndexInSheet=29|OwnerPartId=-1|Location.X=1207|Location.Y=232|Color=8388608|FontID=1|IsHidden=T|Text=Cut Tape|Name=Packaging
|RECORD=41|OwnerIndex=1731|IndexInSheet=30|OwnerPartId=-1|Location.X=1207|Location.Y=232|Color=8388608|FontID=3|IsHidden=T|Text=http://industrial.panasonic.com/cdbs/www-data/pdf/RDA0000/AOA0000C86.pdf|Name=ComponentLink2URL
|RECORD=34|OwnerIndex=1731|IndexInSheet=-1|OwnerPartId=-1|Location.X=1210|Location.Y=180|Orientation=1|Color=8388608|FontID=2|Text=R57|Name=Designator|ReadOnlyState=1
|RECORD=41|OwnerIndex=1731|IndexInSheet=-1|OwnerPartId=-1|Location.X=1220|Location.Y=170|Orientation=1|Color=8388608|FontID=2|Text=4.7K_0402|Name=Comment
|RECORD=44|OwnerIndex=1731
|RECORD=45|OwnerIndex=1767|IndexInSheet=-1|Description=Chip Resistor, 2-Leads, Body 1.05x0.55mm, IPC High Density|UseComponentLibrary=T|ModelName=RESC1005X40X25LL05T05|ModelType=PCBLIB|DatafileCount=1|ModelDatafileEntity0=RESC1005X40X25LL05T05|ModelDatafileKind0=PCBLib|IsCurrent=T|DatalinksLocked=T|DatabaseDatalinksLocked=T
|RECORD=46|OwnerIndex=1768
|RECORD=48|OwnerIndex=1768
|RECORD=41|OwnerIndex=1770|IndexInSheet=-1|OwnerPartId=-1|Color=8388608|FontID=1|IsHidden=T|Text=2D|Name=Available Preview Images
|RECORD=45|OwnerIndex=1767|IndexInSheet=-1|Description=Chip Resistor, 2-Leads, Body 1.05x0.55mm, IPC Low Density|UseComponentLibrary=T|ModelName=RESC1005X40X25ML05T05|ModelType=PCBLIB|DatafileCount=1|ModelDatafileEntity0=RESC1005X40X25ML05T05|ModelDatafileKind0=PCBLib|DatalinksLocked=T|DatabaseDatalinksLocked=T
|RECORD=46|OwnerIndex=1772
|RECORD=48|OwnerIndex=1772
|RECORD=41|OwnerIndex=1774|IndexInSheet=-1|OwnerPartId=-1|Color=8388608|FontID=1|IsHidden=T|Text=2D|Name=Available Preview Images
|RECORD=45|OwnerIndex=1767|IndexInSheet=-1|Description=Chip Resistor, 2-Leads, Body 1.05x0.55mm, IPC Medium Density|UseComponentLibrary=T|ModelName=RESC1005X40X25NL05T05|ModelType=PCBLIB|DatafileCount=1|ModelDatafileEntity0=RESC1005X40X25NL05T05|ModelDatafileKind0=PCBLib|DatalinksLocked=T|DatabaseDatalinksLocked=T
|RECORD=46|OwnerIndex=1776
|RECORD=48|OwnerIndex=1776
|RECORD=41|OwnerIndex=1778|IndexInSheet=-1|OwnerPartId=-1|Color=8388608|FontID=1|IsHidden=T|Text=2D|Name=Available Preview Images
|RECORD=1|LibReference=RES-2|ComponentDescription=Chip Resistor, 4.7 KOhm, +/- 1%, 0.1 W, -55 to 155 degC, 0402 (1005 Metric), RoHS, Tape and Reel|PartCount=2|DisplayModeCount=1|IndexInSheet=189|OwnerPartId=-1|Location.X=1240|Location.Y=200|Orientation=1|CurrentPartId=1|LibraryPath=*|SourceLibraryName=Altium Content Vault|TargetFileName=*|AreaColor=11599871|Color=128|PartIDLocked=T|DesignItemId=CMP-2002-01154-4|AllPinCount=2
|RECORD=2|OwnerIndex=1780|OwnerPartId=1|FormalType=1|Electrical=4|PinConglomerate=33|PinLength=10|Location.X=1240|Location.Y=220|Name=2|Designator=2|PinPropagationDelay=0.000000E+000
|RECORD=2|OwnerIndex=1780|OwnerPartId=1|FormalType=1|Electrical=4|PinConglomerate=35|PinLength=10|Location.X=1240|Location.Y=200|Name=1|Designator=1|PinPropagationDelay=0.000000E+000
|RECORD=6|OwnerIndex=1780|IsNotAccesible=T|IndexInSheet=2|OwnerPartId=1|LineWidth=1|Color=16711680|LocationCount=10|X1=1240|Y1=220|X2=1240|Y2=216|X3=1242|Y3=215|X4=1238|Y4=213|X5=1242|Y5=211|X6=1238|Y6=209|X7=1242|Y7=207|X8=1238|Y8=205|X9=1240|Y9=204|X10=1240|Y10=200
|RECORD=41|OwnerIndex=1780|IndexInSheet=3|OwnerPartId=-1|Location.X=1237|Location.Y=232|Color=8388608|FontID=1|IsHidden=T|Text=0.35 mm|Name=Height
|RECORD=41|OwnerIndex=1780|IndexInSheet=4|OwnerPartId=-1|Location.X=1237|Location.Y=232|Color=8388608|FontID=1|IsHidden=T|Text=Surface Mount|Name=Mounting Technology
|RECORD=41|OwnerIndex=1780|IndexInSheet=5|OwnerPartId=-1|Location.X=1237|Location.Y=232|Color=8388608|FontID=1|IsHidden=T|Text=Yes|Name=REACH SVHC
|RECORD=41|OwnerIndex=1780|IndexInSheet=6|OwnerPartId=-1|Location.X=1237|Location.Y=232|Color=8388608|FontID=1|IsHidden=T|Text=4.7 KOhm|Name=Resistance
|RECORD=41|OwnerIndex=1780|IndexInSheet=7|OwnerPartId=-1|Location.X=1237|Location.Y=232|Color=8388608|FontID=1|IsHidden=T|Text=155 degC|Name=Max Operating Temperature
|RECORD=41|OwnerIndex=1780|IndexInSheet=8|OwnerPartId=-1|Location.X=1237|Location.Y=232|Color=8388608|FontID=1|IsHidden=T|Text=Manufacturer URL|Name=ComponentLink1Description
|RECORD=41|OwnerIndex=1780|IndexInSheet=9|OwnerPartId=-1|Location.X=1237|Location.Y=232|Color=8388608|FontID=1|IsHidden=T|Text=Datasheet|Name=ComponentLink2Description
|RECORD=41|OwnerIndex=1780|IndexInSheet=10|OwnerPartId=-1|Location.X=1237|Location.Y=232|Color=8388608|FontID=1|IsHidden=T|Text=2|Name=Pins
|RECORD=41|OwnerIndex=1780|IndexInSheet=11|OwnerPartId=-1|Location.X=1237|Location.Y=232|Color=8388608|FontID=1|IsHidden=T|Text=0402|Name=PackageReference
|RECORD=41|OwnerIndex=1780|IndexInSheet=12|OwnerPartId=-1|Location.X=1237|Location.Y=232|Color=8388608|FontID=1|IsHidden=T|Text=1%|Name=Tolerance
|RECORD=41|OwnerIndex=1780|IndexInSheet=13|OwnerPartId=-1|Location.X=1237|Location.Y=232|Color=8388608|FontID=1|IsHidden=T|Text=0402|Name=Case Code (Imperial)
|RECORD=41|OwnerIndex=1780|IndexInSheet=14|OwnerPartId=-1|Location.X=1237|Location.Y=232|Color=8388608|FontID=1|IsHidden=T|Text=1 mm|Name=Length
|RECORD=41|OwnerIndex=1780|IndexInSheet=15|OwnerPartId=-1|Location.X=1237|Location.Y=232|Color=8388608|FontID=1|IsHidden=T|Text=2-Pin Surface Mount Device, Body 1 x 0.5 mm|Name=PackageDescription
|RECORD=41|OwnerIndex=1780|IndexInSheet=16|OwnerPartId=-1|Location.X=1237|Location.Y=232|Color=8388608|FontID=1|IsHidden=T|Text=ERJ-2RKF4701X|Name=PartNumber
|RECORD=41|OwnerIndex=1780|IndexInSheet=17|OwnerPartId=-1|Location.X=1237|Location.Y=232|Color=8388608|FontID=1|IsHidden=T|Text=true|Name=RoHSCompliant
|RECORD=41|OwnerIndex=1780|IndexInSheet=18|OwnerPartId=-1|Location.X=1237|Location.Y=232|Color=8388608|FontID=1|IsHidden=T|Text=1|Name=Package Quantity
|RECORD=41|OwnerIndex=1780|IndexInSheet=19|OwnerPartId=-1|Location.X=1237|Location.Y=232|Color=8388608|FontID=1|IsHidden=T|Text=No|Name=Radiation Hardening
|RECORD=41|OwnerIndex=1780|IndexInSheet=20|OwnerPartId=-1|Location.X=1237|Location.Y=232|Color=8388608|FontID=1|IsHidden=T|Text=04/2015|Name=DatasheetVersion
|RECORD=41|OwnerIndex=1780|IndexInSheet=21|OwnerPartId=-1|Location.X=1237|Location.Y=232|Color=8388608|FontID=1|IsHidden=T|Text=0.5 mm|Name=Width
|RECORD=41|OwnerIndex=1780|IndexInSheet=22|OwnerPartId=-1|Location.X=1237|Location.Y=232|Color=8388608|FontID=1|IsHidden=T|Text=1005|Name=Case Code (Metric)
|RECORD=41|OwnerIndex=1780|IndexInSheet=23|OwnerPartId=-1|Location.X=1237|Location.Y=232|Color=8388608|FontID=1|IsHidden=T|Text=50 V|Name=Voltage Rating
|RECORD=41|OwnerIndex=1780|IndexInSheet=24|OwnerPartId=-1|Location.X=1237|Location.Y=232|Color=8388608|FontID=1|IsHidden=T|Text=0402|Name=Case\/Package
|RECORD=41|OwnerIndex=1780|IndexInSheet=25|OwnerPartId=-1|Location.X=1237|Location.Y=232|Color=8388608|FontID=1|IsHidden=T|Text=Surface Mount|Name=Mount
|RECORD=41|OwnerIndex=1780|IndexInSheet=26|OwnerPartId=-1|Location.X=1237|Location.Y=232|Color=8388608|FontID=3|IsHidden=T|Text=http://www.panasonic.com/|Name=ComponentLink1URL
|RECORD=41|OwnerIndex=1780|IndexInSheet=27|OwnerPartId=-1|Location.X=1237|Location.Y=232|Color=8388608|FontID=1|IsHidden=T|Text=-55 degC|Name=Min Operating Temperature
|RECORD=41|OwnerIndex=1780|IndexInSheet=28|OwnerPartId=-1|Location.X=1237|Location.Y=232|Color=8388608|FontID=1|IsHidden=T|Text=100 mW|Name=Power Rating
|RECORD=41|OwnerIndex=1780|IndexInSheet=29|OwnerPartId=-1|Location.X=1237|Location.Y=232|Color=8388608|FontID=1|IsHidden=T|Text=Cut Tape|Name=Packaging
|RECORD=41|OwnerIndex=1780|IndexInSheet=30|OwnerPartId=-1|Location.X=1237|Location.Y=232|Color=8388608|FontID=3|IsHidden=T|Text=http://industrial.panasonic.com/cdbs/www-data/pdf/RDA0000/AOA0000C86.pdf|Name=ComponentLink2URL
|RECORD=34|OwnerIndex=1780|IndexInSheet=-1|OwnerPartId=-1|Location.X=1240|Location.Y=180|Orientation=1|Color=8388608|FontID=2|Text=R58|Name=Designator|ReadOnlyState=1
|RECORD=41|OwnerIndex=1780|IndexInSheet=-1|OwnerPartId=-1|Location.X=1250|Location.Y=170|Orientation=1|Color=8388608|FontID=2|Text=4.7K_0402|Name=Comment
|RECORD=44|OwnerIndex=1780
|RECORD=45|OwnerIndex=1816|IndexInSheet=-1|Description=Chip Resistor, 2-Leads, Body 1.05x0.55mm, IPC High Density|UseComponentLibrary=T|ModelName=RESC1005X40X25LL05T05|ModelType=PCBLIB|DatafileCount=1|ModelDatafileEntity0=RESC1005X40X25LL05T05|ModelDatafileKind0=PCBLib|IsCurrent=T|DatalinksLocked=T|DatabaseDatalinksLocked=T
|RECORD=46|OwnerIndex=1817
|RECORD=48|OwnerIndex=1817
|RECORD=41|OwnerIndex=1819|IndexInSheet=-1|OwnerPartId=-1|Color=8388608|FontID=1|IsHidden=T|Text=2D|Name=Available Preview Images
|RECORD=45|OwnerIndex=1816|IndexInSheet=-1|Description=Chip Resistor, 2-Leads, Body 1.05x0.55mm, IPC Low Density|UseComponentLibrary=T|ModelName=RESC1005X40X25ML05T05|ModelType=PCBLIB|DatafileCount=1|ModelDatafileEntity0=RESC1005X40X25ML05T05|ModelDatafileKind0=PCBLib|DatalinksLocked=T|DatabaseDatalinksLocked=T
|RECORD=46|OwnerIndex=1821
|RECORD=48|OwnerIndex=1821
|RECORD=41|OwnerIndex=1823|IndexInSheet=-1|OwnerPartId=-1|Color=8388608|FontID=1|IsHidden=T|Text=2D|Name=Available Preview Images
|RECORD=45|OwnerIndex=1816|IndexInSheet=-1|Description=Chip Resistor, 2-Leads, Body 1.05x0.55mm, IPC Medium Density|UseComponentLibrary=T|ModelName=RESC1005X40X25NL05T05|ModelType=PCBLIB|DatafileCount=1|ModelDatafileEntity0=RESC1005X40X25NL05T05|ModelDatafileKind0=PCBLib|DatalinksLocked=T|DatabaseDatalinksLocked=T
|RECORD=46|OwnerIndex=1825
|RECORD=48|OwnerIndex=1825
|RECORD=41|OwnerIndex=1827|IndexInSheet=-1|OwnerPartId=-1|Color=8388608|FontID=1|IsHidden=T|Text=2D|Name=Available Preview Images
|RECORD=1|LibReference=RES-2|ComponentDescription=Chip Resistor, 4.7 KOhm, +/- 1%, 0.1 W, -55 to 155 degC, 0402 (1005 Metric), RoHS, Tape and Reel|PartCount=2|DisplayModeCount=1|IndexInSheet=190|OwnerPartId=-1|Location.X=1640|Location.Y=370|Orientation=1|CurrentPartId=1|LibraryPath=*|SourceLibraryName=Altium Content Vault|TargetFileName=*|AreaColor=11599871|Color=128|PartIDLocked=T|DesignItemId=CMP-2002-01154-4|AllPinCount=2
|RECORD=2|OwnerIndex=1829|OwnerPartId=1|FormalType=1|Electrical=4|PinConglomerate=33|PinLength=10|Location.X=1640|Location.Y=390|Name=2|Designator=2|PinPropagationDelay=0.000000E+000
|RECORD=2|OwnerIndex=1829|OwnerPartId=1|FormalType=1|Electrical=4|PinConglomerate=35|PinLength=10|Location.X=1640|Location.Y=370|Name=1|Designator=1|PinPropagationDelay=0.000000E+000
|RECORD=6|OwnerIndex=1829|IsNotAccesible=T|IndexInSheet=2|OwnerPartId=1|LineWidth=1|Color=16711680|LocationCount=10|X1=1640|Y1=390|X2=1640|Y2=386|X3=1642|Y3=385|X4=1638|Y4=383|X5=1642|Y5=381|X6=1638|Y6=379|X7=1642|Y7=377|X8=1638|Y8=375|X9=1640|Y9=374|X10=1640|Y10=370
|RECORD=41|OwnerIndex=1829|IndexInSheet=3|OwnerPartId=-1|Location.X=1637|Location.Y=402|Color=8388608|FontID=1|IsHidden=T|Text=0.35 mm|Name=Height
|RECORD=41|OwnerIndex=1829|IndexInSheet=4|OwnerPartId=-1|Location.X=1637|Location.Y=402|Color=8388608|FontID=1|IsHidden=T|Text=Surface Mount|Name=Mounting Technology
|RECORD=41|OwnerIndex=1829|IndexInSheet=5|OwnerPartId=-1|Location.X=1637|Location.Y=402|Color=8388608|FontID=1|IsHidden=T|Text=Yes|Name=REACH SVHC
|RECORD=41|OwnerIndex=1829|IndexInSheet=6|OwnerPartId=-1|Location.X=1637|Location.Y=402|Color=8388608|FontID=1|IsHidden=T|Text=4.7 KOhm|Name=Resistance
|RECORD=41|OwnerIndex=1829|IndexInSheet=7|OwnerPartId=-1|Location.X=1637|Location.Y=402|Color=8388608|FontID=1|IsHidden=T|Text=155 degC|Name=Max Operating Temperature
|RECORD=41|OwnerIndex=1829|IndexInSheet=8|OwnerPartId=-1|Location.X=1637|Location.Y=402|Color=8388608|FontID=1|IsHidden=T|Text=Manufacturer URL|Name=ComponentLink1Description
|RECORD=41|OwnerIndex=1829|IndexInSheet=9|OwnerPartId=-1|Location.X=1637|Location.Y=402|Color=8388608|FontID=1|IsHidden=T|Text=Datasheet|Name=ComponentLink2Description
|RECORD=41|OwnerIndex=1829|IndexInSheet=10|OwnerPartId=-1|Location.X=1637|Location.Y=402|Color=8388608|FontID=1|IsHidden=T|Text=2|Name=Pins
|RECORD=41|OwnerIndex=1829|IndexInSheet=11|OwnerPartId=-1|Location.X=1637|Location.Y=402|Color=8388608|FontID=1|IsHidden=T|Text=0402|Name=PackageReference
|RECORD=41|OwnerIndex=1829|IndexInSheet=12|OwnerPartId=-1|Location.X=1637|Location.Y=402|Color=8388608|FontID=1|IsHidden=T|Text=1%|Name=Tolerance
|RECORD=41|OwnerIndex=1829|IndexInSheet=13|OwnerPartId=-1|Location.X=1637|Location.Y=402|Color=8388608|FontID=1|IsHidden=T|Text=0402|Name=Case Code (Imperial)
|RECORD=41|OwnerIndex=1829|IndexInSheet=14|OwnerPartId=-1|Location.X=1637|Location.Y=402|Color=8388608|FontID=1|IsHidden=T|Text=1 mm|Name=Length
|RECORD=41|OwnerIndex=1829|IndexInSheet=15|OwnerPartId=-1|Location.X=1637|Location.Y=402|Color=8388608|FontID=1|IsHidden=T|Text=2-Pin Surface Mount Device, Body 1 x 0.5 mm|Name=PackageDescription
|RECORD=41|OwnerIndex=1829|IndexInSheet=16|OwnerPartId=-1|Location.X=1637|Location.Y=402|Color=8388608|FontID=1|IsHidden=T|Text=ERJ-2RKF4701X|Name=PartNumber
|RECORD=41|OwnerIndex=1829|IndexInSheet=17|OwnerPartId=-1|Location.X=1637|Location.Y=402|Color=8388608|FontID=1|IsHidden=T|Text=true|Name=RoHSCompliant
|RECORD=41|OwnerIndex=1829|IndexInSheet=18|OwnerPartId=-1|Location.X=1637|Location.Y=402|Color=8388608|FontID=1|IsHidden=T|Text=1|Name=Package Quantity
|RECORD=41|OwnerIndex=1829|IndexInSheet=19|OwnerPartId=-1|Location.X=1637|Location.Y=402|Color=8388608|FontID=1|IsHidden=T|Text=No|Name=Radiation Hardening
|RECORD=41|OwnerIndex=1829|IndexInSheet=20|OwnerPartId=-1|Location.X=1637|Location.Y=402|Color=8388608|FontID=1|IsHidden=T|Text=04/2015|Name=DatasheetVersion
|RECORD=41|OwnerIndex=1829|IndexInSheet=21|OwnerPartId=-1|Location.X=1637|Location.Y=402|Color=8388608|FontID=1|IsHidden=T|Text=0.5 mm|Name=Width
|RECORD=41|OwnerIndex=1829|IndexInSheet=22|OwnerPartId=-1|Location.X=1637|Location.Y=402|Color=8388608|FontID=1|IsHidden=T|Text=1005|Name=Case Code (Metric)
|RECORD=41|OwnerIndex=1829|IndexInSheet=23|OwnerPartId=-1|Location.X=1637|Location.Y=402|Color=8388608|FontID=1|IsHidden=T|Text=50 V|Name=Voltage Rating
|RECORD=41|OwnerIndex=1829|IndexInSheet=24|OwnerPartId=-1|Location.X=1637|Location.Y=402|Color=8388608|FontID=1|IsHidden=T|Text=0402|Name=Case\/Package
|RECORD=41|OwnerIndex=1829|IndexInSheet=25|OwnerPartId=-1|Location.X=1637|Location.Y=402|Color=8388608|FontID=1|IsHidden=T|Text=Surface Mount|Name=Mount
|RECORD=41|OwnerIndex=1829|IndexInSheet=26|OwnerPartId=-1|Location.X=1637|Location.Y=402|Color=8388608|FontID=3|IsHidden=T|Text=http://www.panasonic.com/|Name=ComponentLink1URL
|RECORD=41|OwnerIndex=1829|IndexInSheet=27|OwnerPartId=-1|Location.X=1637|Location.Y=402|Color=8388608|FontID=1|IsHidden=T|Text=-55 degC|Name=Min Operating Temperature
|RECORD=41|OwnerIndex=1829|IndexInSheet=28|OwnerPartId=-1|Location.X=1637|Location.Y=402|Color=8388608|FontID=1|IsHidden=T|Text=100 mW|Name=Power Rating
|RECORD=41|OwnerIndex=1829|IndexInSheet=29|OwnerPartId=-1|Location.X=1637|Location.Y=402|Color=8388608|FontID=1|IsHidden=T|Text=Cut Tape|Name=Packaging
|RECORD=41|OwnerIndex=1829|IndexInSheet=30|OwnerPartId=-1|Location.X=1637|Location.Y=402|Color=8388608|FontID=3|IsHidden=T|Text=http://industrial.panasonic.com/cdbs/www-data/pdf/RDA0000/AOA0000C86.pdf|Name=ComponentLink2URL
|RECORD=34|OwnerIndex=1829|IndexInSheet=-1|OwnerPartId=-1|Location.X=1640|Location.Y=350|Orientation=1|Color=8388608|FontID=2|Text=R53|Name=Designator|ReadOnlyState=1
|RECORD=41|OwnerIndex=1829|IndexInSheet=-1|OwnerPartId=-1|Location.X=1650|Location.Y=340|Orientation=1|Color=8388608|FontID=2|Text=4.7K_0402|Name=Comment
|RECORD=44|OwnerIndex=1829
|RECORD=45|OwnerIndex=1865|IndexInSheet=-1|Description=Chip Resistor, 2-Leads, Body 1.05x0.55mm, IPC High Density|UseComponentLibrary=T|ModelName=RESC1005X40X25LL05T05|ModelType=PCBLIB|DatafileCount=1|ModelDatafileEntity0=RESC1005X40X25LL05T05|ModelDatafileKind0=PCBLib|IsCurrent=T|DatalinksLocked=T|DatabaseDatalinksLocked=T
|RECORD=46|OwnerIndex=1866
|RECORD=48|OwnerIndex=1866
|RECORD=41|OwnerIndex=1868|IndexInSheet=-1|OwnerPartId=-1|Color=8388608|FontID=1|IsHidden=T|Text=2D|Name=Available Preview Images
|RECORD=45|OwnerIndex=1865|IndexInSheet=-1|Description=Chip Resistor, 2-Leads, Body 1.05x0.55mm, IPC Low Density|UseComponentLibrary=T|ModelName=RESC1005X40X25ML05T05|ModelType=PCBLIB|DatafileCount=1|ModelDatafileEntity0=RESC1005X40X25ML05T05|ModelDatafileKind0=PCBLib|DatalinksLocked=T|DatabaseDatalinksLocked=T
|RECORD=46|OwnerIndex=1870
|RECORD=48|OwnerIndex=1870
|RECORD=41|OwnerIndex=1872|IndexInSheet=-1|OwnerPartId=-1|Color=8388608|FontID=1|IsHidden=T|Text=2D|Name=Available Preview Images
|RECORD=45|OwnerIndex=1865|IndexInSheet=-1|Description=Chip Resistor, 2-Leads, Body 1.05x0.55mm, IPC Medium Density|UseComponentLibrary=T|ModelName=RESC1005X40X25NL05T05|ModelType=PCBLIB|DatafileCount=1|ModelDatafileEntity0=RESC1005X40X25NL05T05|ModelDatafileKind0=PCBLib|DatalinksLocked=T|DatabaseDatalinksLocked=T
|RECORD=46|OwnerIndex=1874
|RECORD=48|OwnerIndex=1874
|RECORD=41|OwnerIndex=1876|IndexInSheet=-1|OwnerPartId=-1|Color=8388608|FontID=1|IsHidden=T|Text=2D|Name=Available Preview Images
|RECORD=1|LibReference=RES-2|ComponentDescription=Chip Resistor, 4.7 KOhm, +/- 1%, 0.1 W, -55 to 155 degC, 0402 (1005 Metric), RoHS, Tape and Reel|PartCount=2|DisplayModeCount=1|IndexInSheet=191|OwnerPartId=-1|Location.X=1640|Location.Y=240|Orientation=1|CurrentPartId=1|LibraryPath=*|SourceLibraryName=Altium Content Vault|TargetFileName=*|AreaColor=11599871|Color=128|PartIDLocked=T|DesignItemId=CMP-2002-01154-4|AllPinCount=2|ComponentKindVersion2=5
|RECORD=2|OwnerIndex=1878|OwnerPartId=1|FormalType=1|Electrical=4|PinConglomerate=33|PinLength=10|Location.X=1640|Location.Y=260|Name=2|Designator=2|PinPropagationDelay=0.000000E+000
|RECORD=2|OwnerIndex=1878|OwnerPartId=1|FormalType=1|Electrical=4|PinConglomerate=35|PinLength=10|Location.X=1640|Location.Y=240|Name=1|Designator=1|PinPropagationDelay=0.000000E+000
|RECORD=6|OwnerIndex=1878|IsNotAccesible=T|IndexInSheet=2|OwnerPartId=1|LineWidth=1|Color=16711680|LocationCount=10|X1=1640|Y1=260|X2=1640|Y2=256|X3=1642|Y3=255|X4=1638|Y4=253|X5=1642|Y5=251|X6=1638|Y6=249|X7=1642|Y7=247|X8=1638|Y8=245|X9=1640|Y9=244|X10=1640|Y10=240
|RECORD=41|OwnerIndex=1878|IndexInSheet=3|OwnerPartId=-1|Location.X=1637|Location.Y=272|Color=8388608|FontID=1|IsHidden=T|Text=0.35 mm|Name=Height
|RECORD=41|OwnerIndex=1878|IndexInSheet=4|OwnerPartId=-1|Location.X=1637|Location.Y=272|Color=8388608|FontID=1|IsHidden=T|Text=Surface Mount|Name=Mounting Technology
|RECORD=41|OwnerIndex=1878|IndexInSheet=5|OwnerPartId=-1|Location.X=1637|Location.Y=272|Color=8388608|FontID=1|IsHidden=T|Text=Yes|Name=REACH SVHC
|RECORD=41|OwnerIndex=1878|IndexInSheet=6|OwnerPartId=-1|Location.X=1637|Location.Y=272|Color=8388608|FontID=1|IsHidden=T|Text=4.7 KOhm|Name=Resistance
|RECORD=41|OwnerIndex=1878|IndexInSheet=7|OwnerPartId=-1|Location.X=1637|Location.Y=272|Color=8388608|FontID=1|IsHidden=T|Text=155 degC|Name=Max Operating Temperature
|RECORD=41|OwnerIndex=1878|IndexInSheet=8|OwnerPartId=-1|Location.X=1637|Location.Y=272|Color=8388608|FontID=1|IsHidden=T|Text=Manufacturer URL|Name=ComponentLink1Description
|RECORD=41|OwnerIndex=1878|IndexInSheet=9|OwnerPartId=-1|Location.X=1637|Location.Y=272|Color=8388608|FontID=1|IsHidden=T|Text=Datasheet|Name=ComponentLink2Description
|RECORD=41|OwnerIndex=1878|IndexInSheet=10|OwnerPartId=-1|Location.X=1637|Location.Y=272|Color=8388608|FontID=1|IsHidden=T|Text=2|Name=Pins
|RECORD=41|OwnerIndex=1878|IndexInSheet=11|OwnerPartId=-1|Location.X=1637|Location.Y=272|Color=8388608|FontID=1|IsHidden=T|Text=0402|Name=PackageReference
|RECORD=41|OwnerIndex=1878|IndexInSheet=12|OwnerPartId=-1|Location.X=1637|Location.Y=272|Color=8388608|FontID=1|IsHidden=T|Text=1%|Name=Tolerance
|RECORD=41|OwnerIndex=1878|IndexInSheet=13|OwnerPartId=-1|Location.X=1637|Location.Y=272|Color=8388608|FontID=1|IsHidden=T|Text=0402|Name=Case Code (Imperial)
|RECORD=41|OwnerIndex=1878|IndexInSheet=14|OwnerPartId=-1|Location.X=1637|Location.Y=272|Color=8388608|FontID=1|IsHidden=T|Text=1 mm|Name=Length
|RECORD=41|OwnerIndex=1878|IndexInSheet=15|OwnerPartId=-1|Location.X=1637|Location.Y=272|Color=8388608|FontID=1|IsHidden=T|Text=2-Pin Surface Mount Device, Body 1 x 0.5 mm|Name=PackageDescription
|RECORD=41|OwnerIndex=1878|IndexInSheet=16|OwnerPartId=-1|Location.X=1637|Location.Y=272|Color=8388608|FontID=1|IsHidden=T|Text=ERJ-2RKF4701X|Name=PartNumber
|RECORD=41|OwnerIndex=1878|IndexInSheet=17|OwnerPartId=-1|Location.X=1637|Location.Y=272|Color=8388608|FontID=1|IsHidden=T|Text=true|Name=RoHSCompliant
|RECORD=41|OwnerIndex=1878|IndexInSheet=18|OwnerPartId=-1|Location.X=1637|Location.Y=272|Color=8388608|FontID=1|IsHidden=T|Text=1|Name=Package Quantity
|RECORD=41|OwnerIndex=1878|IndexInSheet=19|OwnerPartId=-1|Location.X=1637|Location.Y=272|Color=8388608|FontID=1|IsHidden=T|Text=No|Name=Radiation Hardening
|RECORD=41|OwnerIndex=1878|IndexInSheet=20|OwnerPartId=-1|Location.X=1637|Location.Y=272|Color=8388608|FontID=1|IsHidden=T|Text=04/2015|Name=DatasheetVersion
|RECORD=41|OwnerIndex=1878|IndexInSheet=21|OwnerPartId=-1|Location.X=1637|Location.Y=272|Color=8388608|FontID=1|IsHidden=T|Text=0.5 mm|Name=Width
|RECORD=41|OwnerIndex=1878|IndexInSheet=22|OwnerPartId=-1|Location.X=1637|Location.Y=272|Color=8388608|FontID=1|IsHidden=T|Text=1005|Name=Case Code (Metric)
|RECORD=41|OwnerIndex=1878|IndexInSheet=23|OwnerPartId=-1|Location.X=1637|Location.Y=272|Color=8388608|FontID=1|IsHidden=T|Text=50 V|Name=Voltage Rating
|RECORD=41|OwnerIndex=1878|IndexInSheet=24|OwnerPartId=-1|Location.X=1637|Location.Y=272|Color=8388608|FontID=1|IsHidden=T|Text=0402|Name=Case\/Package
|RECORD=41|OwnerIndex=1878|IndexInSheet=25|OwnerPartId=-1|Location.X=1637|Location.Y=272|Color=8388608|FontID=1|IsHidden=T|Text=Surface Mount|Name=Mount
|RECORD=41|OwnerIndex=1878|IndexInSheet=26|OwnerPartId=-1|Location.X=1637|Location.Y=272|Color=8388608|FontID=3|IsHidden=T|Text=http://www.panasonic.com/|Name=ComponentLink1URL
|RECORD=41|OwnerIndex=1878|IndexInSheet=27|OwnerPartId=-1|Location.X=1637|Location.Y=272|Color=8388608|FontID=1|IsHidden=T|Text=-55 degC|Name=Min Operating Temperature
|RECORD=41|OwnerIndex=1878|IndexInSheet=28|OwnerPartId=-1|Location.X=1637|Location.Y=272|Color=8388608|FontID=1|IsHidden=T|Text=100 mW|Name=Power Rating
|RECORD=41|OwnerIndex=1878|IndexInSheet=29|OwnerPartId=-1|Location.X=1637|Location.Y=272|Color=8388608|FontID=1|IsHidden=T|Text=Cut Tape|Name=Packaging
|RECORD=41|OwnerIndex=1878|IndexInSheet=30|OwnerPartId=-1|Location.X=1637|Location.Y=272|Color=8388608|FontID=3|IsHidden=T|Text=http://industrial.panasonic.com/cdbs/www-data/pdf/RDA0000/AOA0000C86.pdf|Name=ComponentLink2URL
|RECORD=34|OwnerIndex=1878|IndexInSheet=-1|OwnerPartId=-1|Location.X=1640|Location.Y=220|Orientation=1|Color=8388608|FontID=2|Text=R56|Name=Designator|ReadOnlyState=1
|RECORD=41|OwnerIndex=1878|IndexInSheet=-1|OwnerPartId=-1|Location.X=1650|Location.Y=210|Orientation=1|Color=8388608|FontID=2|Text=DNI_4.7K_0402|Name=Comment
|RECORD=44|OwnerIndex=1878
|RECORD=45|OwnerIndex=1914|IndexInSheet=-1|Description=Chip Resistor, 2-Leads, Body 1.05x0.55mm, IPC High Density|UseComponentLibrary=T|ModelName=RESC1005X40X25LL05T05|ModelType=PCBLIB|DatafileCount=1|ModelDatafileEntity0=RESC1005X40X25LL05T05|ModelDatafileKind0=PCBLib|IsCurrent=T|DatalinksLocked=T|DatabaseDatalinksLocked=T
|RECORD=46|OwnerIndex=1915
|RECORD=48|OwnerIndex=1915
|RECORD=41|OwnerIndex=1917|IndexInSheet=-1|OwnerPartId=-1|Color=8388608|FontID=1|IsHidden=T|Text=2D|Name=Available Preview Images
|RECORD=45|OwnerIndex=1914|IndexInSheet=-1|Description=Chip Resistor, 2-Leads, Body 1.05x0.55mm, IPC Low Density|UseComponentLibrary=T|ModelName=RESC1005X40X25ML05T05|ModelType=PCBLIB|DatafileCount=1|ModelDatafileEntity0=RESC1005X40X25ML05T05|ModelDatafileKind0=PCBLib|DatalinksLocked=T|DatabaseDatalinksLocked=T
|RECORD=46|OwnerIndex=1919
|RECORD=48|OwnerIndex=1919
|RECORD=41|OwnerIndex=1921|IndexInSheet=-1|OwnerPartId=-1|Color=8388608|FontID=1|IsHidden=T|Text=2D|Name=Available Preview Images
|RECORD=45|OwnerIndex=1914|IndexInSheet=-1|Description=Chip Resistor, 2-Leads, Body 1.05x0.55mm, IPC Medium Density|UseComponentLibrary=T|ModelName=RESC1005X40X25NL05T05|ModelType=PCBLIB|DatafileCount=1|ModelDatafileEntity0=RESC1005X40X25NL05T05|ModelDatafileKind0=PCBLib|DatalinksLocked=T|DatabaseDatalinksLocked=T
|RECORD=46|OwnerIndex=1923
|RECORD=48|OwnerIndex=1923
|RECORD=41|OwnerIndex=1925|IndexInSheet=-1|OwnerPartId=-1|Color=8388608|FontID=1|IsHidden=T|Text=2D|Name=Available Preview Images
|RECORD=1|LibReference=RES-2|ComponentDescription=Chip Resistor, 4.7 KOhm, +/- 1%, 0.1 W, -55 to 155 degC, 0402 (1005 Metric), RoHS, Tape and Reel|PartCount=2|DisplayModeCount=1|IndexInSheet=192|OwnerPartId=-1|Location.X=1240|Location.Y=360|Orientation=2|CurrentPartId=1|LibraryPath=*|SourceLibraryName=Altium Content Vault|TargetFileName=*|AreaColor=11599871|Color=128|PartIDLocked=T|DesignItemId=CMP-2002-01154-4|AllPinCount=2
|RECORD=2|OwnerIndex=1927|OwnerPartId=1|FormalType=1|Electrical=4|PinConglomerate=34|PinLength=10|Location.X=1220|Location.Y=360|Name=2|Designator=2|PinPropagationDelay=0.000000E+000
|RECORD=2|OwnerIndex=1927|OwnerPartId=1|FormalType=1|Electrical=4|PinConglomerate=32|PinLength=10|Location.X=1240|Location.Y=360|Name=1|Designator=1|PinPropagationDelay=0.000000E+000
|RECORD=6|OwnerIndex=1927|IsNotAccesible=T|IndexInSheet=2|OwnerPartId=1|LineWidth=1|Color=16711680|LocationCount=10|X1=1220|Y1=360|X2=1224|Y2=360|X3=1225|Y3=362|X4=1227|Y4=358|X5=1229|Y5=362|X6=1231|Y6=358|X7=1233|Y7=362|X8=1235|Y8=358|X9=1236|Y9=360|X10=1240|Y10=360
|RECORD=41|OwnerIndex=1927|IndexInSheet=3|OwnerPartId=-1|Location.X=1208|Location.Y=363|Color=8388608|FontID=1|IsHidden=T|Text=0.35 mm|Name=Height
|RECORD=41|OwnerIndex=1927|IndexInSheet=4|OwnerPartId=-1|Location.X=1208|Location.Y=363|Color=8388608|FontID=1|IsHidden=T|Text=Surface Mount|Name=Mounting Technology
|RECORD=41|OwnerIndex=1927|IndexInSheet=5|OwnerPartId=-1|Location.X=1208|Location.Y=363|Color=8388608|FontID=1|IsHidden=T|Text=Yes|Name=REACH SVHC
|RECORD=41|OwnerIndex=1927|IndexInSheet=6|OwnerPartId=-1|Location.X=1208|Location.Y=363|Color=8388608|FontID=1|IsHidden=T|Text=4.7 KOhm|Name=Resistance
|RECORD=41|OwnerIndex=1927|IndexInSheet=7|OwnerPartId=-1|Location.X=1208|Location.Y=363|Color=8388608|FontID=1|IsHidden=T|Text=155 degC|Name=Max Operating Temperature
|RECORD=41|OwnerIndex=1927|IndexInSheet=8|OwnerPartId=-1|Location.X=1208|Location.Y=363|Color=8388608|FontID=1|IsHidden=T|Text=Manufacturer URL|Name=ComponentLink1Description
|RECORD=41|OwnerIndex=1927|IndexInSheet=9|OwnerPartId=-1|Location.X=1208|Location.Y=363|Color=8388608|FontID=1|IsHidden=T|Text=Datasheet|Name=ComponentLink2Description
|RECORD=41|OwnerIndex=1927|IndexInSheet=10|OwnerPartId=-1|Location.X=1208|Location.Y=363|Color=8388608|FontID=1|IsHidden=T|Text=2|Name=Pins
|RECORD=41|OwnerIndex=1927|IndexInSheet=11|OwnerPartId=-1|Location.X=1208|Location.Y=363|Color=8388608|FontID=1|IsHidden=T|Text=0402|Name=PackageReference
|RECORD=41|OwnerIndex=1927|IndexInSheet=12|OwnerPartId=-1|Location.X=1208|Location.Y=363|Color=8388608|FontID=1|IsHidden=T|Text=1%|Name=Tolerance
|RECORD=41|OwnerIndex=1927|IndexInSheet=13|OwnerPartId=-1|Location.X=1208|Location.Y=363|Color=8388608|FontID=1|IsHidden=T|Text=0402|Name=Case Code (Imperial)
|RECORD=41|OwnerIndex=1927|IndexInSheet=14|OwnerPartId=-1|Location.X=1208|Location.Y=363|Color=8388608|FontID=1|IsHidden=T|Text=1 mm|Name=Length
|RECORD=41|OwnerIndex=1927|IndexInSheet=15|OwnerPartId=-1|Location.X=1208|Location.Y=363|Color=8388608|FontID=1|IsHidden=T|Text=2-Pin Surface Mount Device, Body 1 x 0.5 mm|Name=PackageDescription
|RECORD=41|OwnerIndex=1927|IndexInSheet=16|OwnerPartId=-1|Location.X=1208|Location.Y=363|Color=8388608|FontID=1|IsHidden=T|Text=ERJ-2RKF4701X|Name=PartNumber
|RECORD=41|OwnerIndex=1927|IndexInSheet=17|OwnerPartId=-1|Location.X=1208|Location.Y=363|Color=8388608|FontID=1|IsHidden=T|Text=true|Name=RoHSCompliant
|RECORD=41|OwnerIndex=1927|IndexInSheet=18|OwnerPartId=-1|Location.X=1208|Location.Y=363|Color=8388608|FontID=1|IsHidden=T|Text=1|Name=Package Quantity
|RECORD=41|OwnerIndex=1927|IndexInSheet=19|OwnerPartId=-1|Location.X=1208|Location.Y=363|Color=8388608|FontID=1|IsHidden=T|Text=No|Name=Radiation Hardening
|RECORD=41|OwnerIndex=1927|IndexInSheet=20|OwnerPartId=-1|Location.X=1208|Location.Y=363|Color=8388608|FontID=1|IsHidden=T|Text=04/2015|Name=DatasheetVersion
|RECORD=41|OwnerIndex=1927|IndexInSheet=21|OwnerPartId=-1|Location.X=1208|Location.Y=363|Color=8388608|FontID=1|IsHidden=T|Text=0.5 mm|Name=Width
|RECORD=41|OwnerIndex=1927|IndexInSheet=22|OwnerPartId=-1|Location.X=1208|Location.Y=363|Color=8388608|FontID=1|IsHidden=T|Text=1005|Name=Case Code (Metric)
|RECORD=41|OwnerIndex=1927|IndexInSheet=23|OwnerPartId=-1|Location.X=1208|Location.Y=363|Color=8388608|FontID=1|IsHidden=T|Text=50 V|Name=Voltage Rating
|RECORD=41|OwnerIndex=1927|IndexInSheet=24|OwnerPartId=-1|Location.X=1208|Location.Y=363|Color=8388608|FontID=1|IsHidden=T|Text=0402|Name=Case\/Package
|RECORD=41|OwnerIndex=1927|IndexInSheet=25|OwnerPartId=-1|Location.X=1208|Location.Y=363|Color=8388608|FontID=1|IsHidden=T|Text=Surface Mount|Name=Mount
|RECORD=41|OwnerIndex=1927|IndexInSheet=26|OwnerPartId=-1|Location.X=1208|Location.Y=363|Color=8388608|FontID=3|IsHidden=T|Text=http://www.panasonic.com/|Name=ComponentLink1URL
|RECORD=41|OwnerIndex=1927|IndexInSheet=27|OwnerPartId=-1|Location.X=1208|Location.Y=363|Color=8388608|FontID=1|IsHidden=T|Text=-55 degC|Name=Min Operating Temperature
|RECORD=41|OwnerIndex=1927|IndexInSheet=28|OwnerPartId=-1|Location.X=1208|Location.Y=363|Color=8388608|FontID=1|IsHidden=T|Text=100 mW|Name=Power Rating
|RECORD=41|OwnerIndex=1927|IndexInSheet=29|OwnerPartId=-1|Location.X=1208|Location.Y=363|Color=8388608|FontID=1|IsHidden=T|Text=Cut Tape|Name=Packaging
|RECORD=41|OwnerIndex=1927|IndexInSheet=30|OwnerPartId=-1|Location.X=1208|Location.Y=363|Color=8388608|FontID=3|IsHidden=T|Text=http://industrial.panasonic.com/cdbs/www-data/pdf/RDA0000/AOA0000C86.pdf|Name=ComponentLink2URL
|RECORD=34|OwnerIndex=1927|IndexInSheet=-1|OwnerPartId=-1|Location.X=1219|Location.Y=363|Color=8388608|FontID=1|Text=R52|Name=Designator|ReadOnlyState=1
|RECORD=41|OwnerIndex=1927|IndexInSheet=-1|OwnerPartId=-1|Location.X=1219|Location.Y=347|Color=8388608|FontID=1|Text=4.7K_0402|Name=Comment
|RECORD=44|OwnerIndex=1927
|RECORD=45|OwnerIndex=1963|IndexInSheet=-1|Description=Chip Resistor, 2-Leads, Body 1.05x0.55mm, IPC High Density|UseComponentLibrary=T|ModelName=RESC1005X40X25LL05T05|ModelType=PCBLIB|DatafileCount=1|ModelDatafileEntity0=RESC1005X40X25LL05T05|ModelDatafileKind0=PCBLib|IsCurrent=T|DatalinksLocked=T|DatabaseDatalinksLocked=T
|RECORD=46|OwnerIndex=1964
|RECORD=48|OwnerIndex=1964
|RECORD=41|OwnerIndex=1966|IndexInSheet=-1|OwnerPartId=-1|Color=8388608|FontID=1|IsHidden=T|Text=2D|Name=Available Preview Images
|RECORD=45|OwnerIndex=1963|IndexInSheet=-1|Description=Chip Resistor, 2-Leads, Body 1.05x0.55mm, IPC Low Density|UseComponentLibrary=T|ModelName=RESC1005X40X25ML05T05|ModelType=PCBLIB|DatafileCount=1|ModelDatafileEntity0=RESC1005X40X25ML05T05|ModelDatafileKind0=PCBLib|DatalinksLocked=T|DatabaseDatalinksLocked=T
|RECORD=46|OwnerIndex=1968
|RECORD=48|OwnerIndex=1968
|RECORD=41|OwnerIndex=1970|IndexInSheet=-1|OwnerPartId=-1|Color=8388608|FontID=1|IsHidden=T|Text=2D|Name=Available Preview Images
|RECORD=45|OwnerIndex=1963|IndexInSheet=-1|Description=Chip Resistor, 2-Leads, Body 1.05x0.55mm, IPC Medium Density|UseComponentLibrary=T|ModelName=RESC1005X40X25NL05T05|ModelType=PCBLIB|DatafileCount=1|ModelDatafileEntity0=RESC1005X40X25NL05T05|ModelDatafileKind0=PCBLib|DatalinksLocked=T|DatabaseDatalinksLocked=T
|RECORD=46|OwnerIndex=1972
|RECORD=48|OwnerIndex=1972
|RECORD=41|OwnerIndex=1974|IndexInSheet=-1|OwnerPartId=-1|Color=8388608|FontID=1|IsHidden=T|Text=2D|Name=Available Preview Images
|RECORD=1|LibReference=RES-2|ComponentDescription=Chip Resistor, 4.7 KOhm, +/- 1%, 0.1 W, -55 to 155 degC, 0402 (1005 Metric), RoHS, Tape and Reel|PartCount=2|DisplayModeCount=1|IndexInSheet=193|OwnerPartId=-1|Location.X=1590|Location.Y=460|Orientation=2|CurrentPartId=1|LibraryPath=*|SourceLibraryName=Altium Content Vault|TargetFileName=*|AreaColor=11599871|Color=128|PartIDLocked=T|DesignItemId=CMP-2002-01154-4|AllPinCount=2
|RECORD=2|OwnerIndex=1976|OwnerPartId=1|FormalType=1|Electrical=4|PinConglomerate=34|PinLength=10|Location.X=1570|Location.Y=460|Name=2|Designator=2|PinPropagationDelay=0.000000E+000
|RECORD=2|OwnerIndex=1976|OwnerPartId=1|FormalType=1|Electrical=4|PinConglomerate=32|PinLength=10|Location.X=1590|Location.Y=460|Name=1|Designator=1|PinPropagationDelay=0.000000E+000
|RECORD=6|OwnerIndex=1976|IsNotAccesible=T|IndexInSheet=2|OwnerPartId=1|LineWidth=1|Color=16711680|LocationCount=10|X1=1570|Y1=460|X2=1574|Y2=460|X3=1575|Y3=462|X4=1577|Y4=458|X5=1579|Y5=462|X6=1581|Y6=458|X7=1583|Y7=462|X8=1585|Y8=458|X9=1586|Y9=460|X10=1590|Y10=460
|RECORD=41|OwnerIndex=1976|IndexInSheet=3|OwnerPartId=-1|Location.X=1558|Location.Y=463|Color=8388608|FontID=1|IsHidden=T|Text=0.35 mm|Name=Height
|RECORD=41|OwnerIndex=1976|IndexInSheet=4|OwnerPartId=-1|Location.X=1558|Location.Y=463|Color=8388608|FontID=1|IsHidden=T|Text=Surface Mount|Name=Mounting Technology
|RECORD=41|OwnerIndex=1976|IndexInSheet=5|OwnerPartId=-1|Location.X=1558|Location.Y=463|Color=8388608|FontID=1|IsHidden=T|Text=Yes|Name=REACH SVHC
|RECORD=41|OwnerIndex=1976|IndexInSheet=6|OwnerPartId=-1|Location.X=1558|Location.Y=463|Color=8388608|FontID=1|IsHidden=T|Text=4.7 KOhm|Name=Resistance
|RECORD=41|OwnerIndex=1976|IndexInSheet=7|OwnerPartId=-1|Location.X=1558|Location.Y=463|Color=8388608|FontID=1|IsHidden=T|Text=155 degC|Name=Max Operating Temperature
|RECORD=41|OwnerIndex=1976|IndexInSheet=8|OwnerPartId=-1|Location.X=1558|Location.Y=463|Color=8388608|FontID=1|IsHidden=T|Text=Manufacturer URL|Name=ComponentLink1Description
|RECORD=41|OwnerIndex=1976|IndexInSheet=9|OwnerPartId=-1|Location.X=1558|Location.Y=463|Color=8388608|FontID=1|IsHidden=T|Text=Datasheet|Name=ComponentLink2Description
|RECORD=41|OwnerIndex=1976|IndexInSheet=10|OwnerPartId=-1|Location.X=1558|Location.Y=463|Color=8388608|FontID=1|IsHidden=T|Text=2|Name=Pins
|RECORD=41|OwnerIndex=1976|IndexInSheet=11|OwnerPartId=-1|Location.X=1558|Location.Y=463|Color=8388608|FontID=1|IsHidden=T|Text=0402|Name=PackageReference
|RECORD=41|OwnerIndex=1976|IndexInSheet=12|OwnerPartId=-1|Location.X=1558|Location.Y=463|Color=8388608|FontID=1|IsHidden=T|Text=1%|Name=Tolerance
|RECORD=41|OwnerIndex=1976|IndexInSheet=13|OwnerPartId=-1|Location.X=1558|Location.Y=463|Color=8388608|FontID=1|IsHidden=T|Text=0402|Name=Case Code (Imperial)
|RECORD=41|OwnerIndex=1976|IndexInSheet=14|OwnerPartId=-1|Location.X=1558|Location.Y=463|Color=8388608|FontID=1|IsHidden=T|Text=1 mm|Name=Length
|RECORD=41|OwnerIndex=1976|IndexInSheet=15|OwnerPartId=-1|Location.X=1558|Location.Y=463|Color=8388608|FontID=1|IsHidden=T|Text=2-Pin Surface Mount Device, Body 1 x 0.5 mm|Name=PackageDescription
|RECORD=41|OwnerIndex=1976|IndexInSheet=16|OwnerPartId=-1|Location.X=1558|Location.Y=463|Color=8388608|FontID=1|IsHidden=T|Text=ERJ-2RKF4701X|Name=PartNumber
|RECORD=41|OwnerIndex=1976|IndexInSheet=17|OwnerPartId=-1|Location.X=1558|Location.Y=463|Color=8388608|FontID=1|IsHidden=T|Text=true|Name=RoHSCompliant
|RECORD=41|OwnerIndex=1976|IndexInSheet=18|OwnerPartId=-1|Location.X=1558|Location.Y=463|Color=8388608|FontID=1|IsHidden=T|Text=1|Name=Package Quantity
|RECORD=41|OwnerIndex=1976|IndexInSheet=19|OwnerPartId=-1|Location.X=1558|Location.Y=463|Color=8388608|FontID=1|IsHidden=T|Text=No|Name=Radiation Hardening
|RECORD=41|OwnerIndex=1976|IndexInSheet=20|OwnerPartId=-1|Location.X=1558|Location.Y=463|Color=8388608|FontID=1|IsHidden=T|Text=04/2015|Name=DatasheetVersion
|RECORD=41|OwnerIndex=1976|IndexInSheet=21|OwnerPartId=-1|Location.X=1558|Location.Y=463|Color=8388608|FontID=1|IsHidden=T|Text=0.5 mm|Name=Width
|RECORD=41|OwnerIndex=1976|IndexInSheet=22|OwnerPartId=-1|Location.X=1558|Location.Y=463|Color=8388608|FontID=1|IsHidden=T|Text=1005|Name=Case Code (Metric)
|RECORD=41|OwnerIndex=1976|IndexInSheet=23|OwnerPartId=-1|Location.X=1558|Location.Y=463|Color=8388608|FontID=1|IsHidden=T|Text=50 V|Name=Voltage Rating
|RECORD=41|OwnerIndex=1976|IndexInSheet=24|OwnerPartId=-1|Location.X=1558|Location.Y=463|Color=8388608|FontID=1|IsHidden=T|Text=0402|Name=Case\/Package
|RECORD=41|OwnerIndex=1976|IndexInSheet=25|OwnerPartId=-1|Location.X=1558|Location.Y=463|Color=8388608|FontID=1|IsHidden=T|Text=Surface Mount|Name=Mount
|RECORD=41|OwnerIndex=1976|IndexInSheet=26|OwnerPartId=-1|Location.X=1558|Location.Y=463|Color=8388608|FontID=3|IsHidden=T|Text=http://www.panasonic.com/|Name=ComponentLink1URL
|RECORD=41|OwnerIndex=1976|IndexInSheet=27|OwnerPartId=-1|Location.X=1558|Location.Y=463|Color=8388608|FontID=1|IsHidden=T|Text=-55 degC|Name=Min Operating Temperature
|RECORD=41|OwnerIndex=1976|IndexInSheet=28|OwnerPartId=-1|Location.X=1558|Location.Y=463|Color=8388608|FontID=1|IsHidden=T|Text=100 mW|Name=Power Rating
|RECORD=41|OwnerIndex=1976|IndexInSheet=29|OwnerPartId=-1|Location.X=1558|Location.Y=463|Color=8388608|FontID=1|IsHidden=T|Text=Cut Tape|Name=Packaging
|RECORD=41|OwnerIndex=1976|IndexInSheet=30|OwnerPartId=-1|Location.X=1558|Location.Y=463|Color=8388608|FontID=3|IsHidden=T|Text=http://industrial.panasonic.com/cdbs/www-data/pdf/RDA0000/AOA0000C86.pdf|Name=ComponentLink2URL
|RECORD=34|OwnerIndex=1976|IndexInSheet=-1|OwnerPartId=-1|Location.X=1569|Location.Y=463|Color=8388608|FontID=1|Text=R50|Name=Designator|ReadOnlyState=1
|RECORD=41|OwnerIndex=1976|IndexInSheet=-1|OwnerPartId=-1|Location.X=1569|Location.Y=447|Color=8388608|FontID=1|Text=4.7K_0402|Name=Comment
|RECORD=44|OwnerIndex=1976
|RECORD=45|OwnerIndex=2012|IndexInSheet=-1|Description=Chip Resistor, 2-Leads, Body 1.05x0.55mm, IPC High Density|UseComponentLibrary=T|ModelName=RESC1005X40X25LL05T05|ModelType=PCBLIB|DatafileCount=1|ModelDatafileEntity0=RESC1005X40X25LL05T05|ModelDatafileKind0=PCBLib|IsCurrent=T|DatalinksLocked=T|DatabaseDatalinksLocked=T
|RECORD=46|OwnerIndex=2013
|RECORD=48|OwnerIndex=2013
|RECORD=41|OwnerIndex=2015|IndexInSheet=-1|OwnerPartId=-1|Color=8388608|FontID=1|IsHidden=T|Text=2D|Name=Available Preview Images
|RECORD=45|OwnerIndex=2012|IndexInSheet=-1|Description=Chip Resistor, 2-Leads, Body 1.05x0.55mm, IPC Low Density|UseComponentLibrary=T|ModelName=RESC1005X40X25ML05T05|ModelType=PCBLIB|DatafileCount=1|ModelDatafileEntity0=RESC1005X40X25ML05T05|ModelDatafileKind0=PCBLib|DatalinksLocked=T|DatabaseDatalinksLocked=T
|RECORD=46|OwnerIndex=2017
|RECORD=48|OwnerIndex=2017
|RECORD=41|OwnerIndex=2019|IndexInSheet=-1|OwnerPartId=-1|Color=8388608|FontID=1|IsHidden=T|Text=2D|Name=Available Preview Images
|RECORD=45|OwnerIndex=2012|IndexInSheet=-1|Description=Chip Resistor, 2-Leads, Body 1.05x0.55mm, IPC Medium Density|UseComponentLibrary=T|ModelName=RESC1005X40X25NL05T05|ModelType=PCBLIB|DatafileCount=1|ModelDatafileEntity0=RESC1005X40X25NL05T05|ModelDatafileKind0=PCBLib|DatalinksLocked=T|DatabaseDatalinksLocked=T
|RECORD=46|OwnerIndex=2021
|RECORD=48|OwnerIndex=2021
|RECORD=41|OwnerIndex=2023|IndexInSheet=-1|OwnerPartId=-1|Color=8388608|FontID=1|IsHidden=T|Text=2D|Name=Available Preview Images
|RECORD=1|LibReference=RES-2|ComponentDescription=Chip Resistor, 4.7 KOhm, +/- 1%, 0.1 W, -55 to 155 degC, 0402 (1005 Metric), RoHS, Tape and Reel|PartCount=2|DisplayModeCount=1|IndexInSheet=194|OwnerPartId=-1|Location.X=1550|Location.Y=430|Orientation=2|CurrentPartId=1|LibraryPath=*|SourceLibraryName=Altium Content Vault|TargetFileName=*|AreaColor=11599871|Color=128|PartIDLocked=T|DesignItemId=CMP-2002-01154-4|AllPinCount=2
|RECORD=2|OwnerIndex=2025|OwnerPartId=1|FormalType=1|Electrical=4|PinConglomerate=34|PinLength=10|Location.X=1530|Location.Y=430|Name=2|Designator=2|PinPropagationDelay=0.000000E+000
|RECORD=2|OwnerIndex=2025|OwnerPartId=1|FormalType=1|Electrical=4|PinConglomerate=32|PinLength=10|Location.X=1550|Location.Y=430|Name=1|Designator=1|PinPropagationDelay=0.000000E+000
|RECORD=6|OwnerIndex=2025|IsNotAccesible=T|IndexInSheet=2|OwnerPartId=1|LineWidth=1|Color=16711680|LocationCount=10|X1=1530|Y1=430|X2=1534|Y2=430|X3=1535|Y3=432|X4=1537|Y4=428|X5=1539|Y5=432|X6=1541|Y6=428|X7=1543|Y7=432|X8=1545|Y8=428|X9=1546|Y9=430|X10=1550|Y10=430
|RECORD=41|OwnerIndex=2025|IndexInSheet=3|OwnerPartId=-1|Location.X=1518|Location.Y=433|Color=8388608|FontID=1|IsHidden=T|Text=0.35 mm|Name=Height
|RECORD=41|OwnerIndex=2025|IndexInSheet=4|OwnerPartId=-1|Location.X=1518|Location.Y=433|Color=8388608|FontID=1|IsHidden=T|Text=Surface Mount|Name=Mounting Technology
|RECORD=41|OwnerIndex=2025|IndexInSheet=5|OwnerPartId=-1|Location.X=1518|Location.Y=433|Color=8388608|FontID=1|IsHidden=T|Text=Yes|Name=REACH SVHC
|RECORD=41|OwnerIndex=2025|IndexInSheet=6|OwnerPartId=-1|Location.X=1518|Location.Y=433|Color=8388608|FontID=1|IsHidden=T|Text=4.7 KOhm|Name=Resistance
|RECORD=41|OwnerIndex=2025|IndexInSheet=7|OwnerPartId=-1|Location.X=1518|Location.Y=433|Color=8388608|FontID=1|IsHidden=T|Text=155 degC|Name=Max Operating Temperature
|RECORD=41|OwnerIndex=2025|IndexInSheet=8|OwnerPartId=-1|Location.X=1518|Location.Y=433|Color=8388608|FontID=1|IsHidden=T|Text=Manufacturer URL|Name=ComponentLink1Description
|RECORD=41|OwnerIndex=2025|IndexInSheet=9|OwnerPartId=-1|Location.X=1518|Location.Y=433|Color=8388608|FontID=1|IsHidden=T|Text=Datasheet|Name=ComponentLink2Description
|RECORD=41|OwnerIndex=2025|IndexInSheet=10|OwnerPartId=-1|Location.X=1518|Location.Y=433|Color=8388608|FontID=1|IsHidden=T|Text=2|Name=Pins
|RECORD=41|OwnerIndex=2025|IndexInSheet=11|OwnerPartId=-1|Location.X=1518|Location.Y=433|Color=8388608|FontID=1|IsHidden=T|Text=0402|Name=PackageReference
|RECORD=41|OwnerIndex=2025|IndexInSheet=12|OwnerPartId=-1|Location.X=1518|Location.Y=433|Color=8388608|FontID=1|IsHidden=T|Text=1%|Name=Tolerance
|RECORD=41|OwnerIndex=2025|IndexInSheet=13|OwnerPartId=-1|Location.X=1518|Location.Y=433|Color=8388608|FontID=1|IsHidden=T|Text=0402|Name=Case Code (Imperial)
|RECORD=41|OwnerIndex=2025|IndexInSheet=14|OwnerPartId=-1|Location.X=1518|Location.Y=433|Color=8388608|FontID=1|IsHidden=T|Text=1 mm|Name=Length
|RECORD=41|OwnerIndex=2025|IndexInSheet=15|OwnerPartId=-1|Location.X=1518|Location.Y=433|Color=8388608|FontID=1|IsHidden=T|Text=2-Pin Surface Mount Device, Body 1 x 0.5 mm|Name=PackageDescription
|RECORD=41|OwnerIndex=2025|IndexInSheet=16|OwnerPartId=-1|Location.X=1518|Location.Y=433|Color=8388608|FontID=1|IsHidden=T|Text=ERJ-2RKF4701X|Name=PartNumber
|RECORD=41|OwnerIndex=2025|IndexInSheet=17|OwnerPartId=-1|Location.X=1518|Location.Y=433|Color=8388608|FontID=1|IsHidden=T|Text=true|Name=RoHSCompliant
|RECORD=41|OwnerIndex=2025|IndexInSheet=18|OwnerPartId=-1|Location.X=1518|Location.Y=433|Color=8388608|FontID=1|IsHidden=T|Text=1|Name=Package Quantity
|RECORD=41|OwnerIndex=2025|IndexInSheet=19|OwnerPartId=-1|Location.X=1518|Location.Y=433|Color=8388608|FontID=1|IsHidden=T|Text=No|Name=Radiation Hardening
|RECORD=41|OwnerIndex=2025|IndexInSheet=20|OwnerPartId=-1|Location.X=1518|Location.Y=433|Color=8388608|FontID=1|IsHidden=T|Text=04/2015|Name=DatasheetVersion
|RECORD=41|OwnerIndex=2025|IndexInSheet=21|OwnerPartId=-1|Location.X=1518|Location.Y=433|Color=8388608|FontID=1|IsHidden=T|Text=0.5 mm|Name=Width
|RECORD=41|OwnerIndex=2025|IndexInSheet=22|OwnerPartId=-1|Location.X=1518|Location.Y=433|Color=8388608|FontID=1|IsHidden=T|Text=1005|Name=Case Code (Metric)
|RECORD=41|OwnerIndex=2025|IndexInSheet=23|OwnerPartId=-1|Location.X=1518|Location.Y=433|Color=8388608|FontID=1|IsHidden=T|Text=50 V|Name=Voltage Rating
|RECORD=41|OwnerIndex=2025|IndexInSheet=24|OwnerPartId=-1|Location.X=1518|Location.Y=433|Color=8388608|FontID=1|IsHidden=T|Text=0402|Name=Case\/Package
|RECORD=41|OwnerIndex=2025|IndexInSheet=25|OwnerPartId=-1|Location.X=1518|Location.Y=433|Color=8388608|FontID=1|IsHidden=T|Text=Surface Mount|Name=Mount
|RECORD=41|OwnerIndex=2025|IndexInSheet=26|OwnerPartId=-1|Location.X=1518|Location.Y=433|Color=8388608|FontID=3|IsHidden=T|Text=http://www.panasonic.com/|Name=ComponentLink1URL
|RECORD=41|OwnerIndex=2025|IndexInSheet=27|OwnerPartId=-1|Location.X=1518|Location.Y=433|Color=8388608|FontID=1|IsHidden=T|Text=-55 degC|Name=Min Operating Temperature
|RECORD=41|OwnerIndex=2025|IndexInSheet=28|OwnerPartId=-1|Location.X=1518|Location.Y=433|Color=8388608|FontID=1|IsHidden=T|Text=100 mW|Name=Power Rating
|RECORD=41|OwnerIndex=2025|IndexInSheet=29|OwnerPartId=-1|Location.X=1518|Location.Y=433|Color=8388608|FontID=1|IsHidden=T|Text=Cut Tape|Name=Packaging
|RECORD=41|OwnerIndex=2025|IndexInSheet=30|OwnerPartId=-1|Location.X=1518|Location.Y=433|Color=8388608|FontID=3|IsHidden=T|Text=http://industrial.panasonic.com/cdbs/www-data/pdf/RDA0000/AOA0000C86.pdf|Name=ComponentLink2URL
|RECORD=34|OwnerIndex=2025|IndexInSheet=-1|OwnerPartId=-1|Location.X=1529|Location.Y=433|Color=8388608|FontID=1|Text=R51|Name=Designator|ReadOnlyState=1
|RECORD=41|OwnerIndex=2025|IndexInSheet=-1|OwnerPartId=-1|Location.X=1529|Location.Y=417|Color=8388608|FontID=1|Text=4.7K_0402|Name=Comment
|RECORD=44|OwnerIndex=2025
|RECORD=45|OwnerIndex=2061|IndexInSheet=-1|Description=Chip Resistor, 2-Leads, Body 1.05x0.55mm, IPC High Density|UseComponentLibrary=T|ModelName=RESC1005X40X25LL05T05|ModelType=PCBLIB|DatafileCount=1|ModelDatafileEntity0=RESC1005X40X25LL05T05|ModelDatafileKind0=PCBLib|IsCurrent=T|DatalinksLocked=T|DatabaseDatalinksLocked=T
|RECORD=46|OwnerIndex=2062
|RECORD=48|OwnerIndex=2062
|RECORD=41|OwnerIndex=2064|IndexInSheet=-1|OwnerPartId=-1|Color=8388608|FontID=1|IsHidden=T|Text=2D|Name=Available Preview Images
|RECORD=45|OwnerIndex=2061|IndexInSheet=-1|Description=Chip Resistor, 2-Leads, Body 1.05x0.55mm, IPC Low Density|UseComponentLibrary=T|ModelName=RESC1005X40X25ML05T05|ModelType=PCBLIB|DatafileCount=1|ModelDatafileEntity0=RESC1005X40X25ML05T05|ModelDatafileKind0=PCBLib|DatalinksLocked=T|DatabaseDatalinksLocked=T
|RECORD=46|OwnerIndex=2066
|RECORD=48|OwnerIndex=2066
|RECORD=41|OwnerIndex=2068|IndexInSheet=-1|OwnerPartId=-1|Color=8388608|FontID=1|IsHidden=T|Text=2D|Name=Available Preview Images
|RECORD=45|OwnerIndex=2061|IndexInSheet=-1|Description=Chip Resistor, 2-Leads, Body 1.05x0.55mm, IPC Medium Density|UseComponentLibrary=T|ModelName=RESC1005X40X25NL05T05|ModelType=PCBLIB|DatafileCount=1|ModelDatafileEntity0=RESC1005X40X25NL05T05|ModelDatafileKind0=PCBLib|DatalinksLocked=T|DatabaseDatalinksLocked=T
|RECORD=46|OwnerIndex=2070
|RECORD=48|OwnerIndex=2070
|RECORD=41|OwnerIndex=2072|IndexInSheet=-1|OwnerPartId=-1|Color=8388608|FontID=1|IsHidden=T|Text=2D|Name=Available Preview Images
|RECORD=1|LibReference=RES-2|ComponentDescription=Chip Resistor, 4.7 KOhm, +/- 1%, 0.1 W, -55 to 155 degC, 0402 (1005 Metric), RoHS, Tape and Reel|PartCount=2|DisplayModeCount=1|IndexInSheet=195|OwnerPartId=-1|Location.X=1540|Location.Y=270|Orientation=2|CurrentPartId=1|LibraryPath=*|SourceLibraryName=Altium Content Vault|TargetFileName=*|AreaColor=11599871|Color=128|PartIDLocked=T|DesignItemId=CMP-2002-01154-4|AllPinCount=2
|RECORD=2|OwnerIndex=2074|OwnerPartId=1|FormalType=1|Electrical=4|PinConglomerate=34|PinLength=10|Location.X=1520|Location.Y=270|Name=2|Designator=2|PinPropagationDelay=0.000000E+000
|RECORD=2|OwnerIndex=2074|OwnerPartId=1|FormalType=1|Electrical=4|PinConglomerate=32|PinLength=10|Location.X=1540|Location.Y=270|Name=1|Designator=1|PinPropagationDelay=0.000000E+000
|RECORD=6|OwnerIndex=2074|IsNotAccesible=T|IndexInSheet=2|OwnerPartId=1|LineWidth=1|Color=16711680|LocationCount=10|X1=1520|Y1=270|X2=1524|Y2=270|X3=1525|Y3=272|X4=1527|Y4=268|X5=1529|Y5=272|X6=1531|Y6=268|X7=1533|Y7=272|X8=1535|Y8=268|X9=1536|Y9=270|X10=1540|Y10=270
|RECORD=41|OwnerIndex=2074|IndexInSheet=3|OwnerPartId=-1|Location.X=1508|Location.Y=273|Color=8388608|FontID=1|IsHidden=T|Text=0.35 mm|Name=Height
|RECORD=41|OwnerIndex=2074|IndexInSheet=4|OwnerPartId=-1|Location.X=1508|Location.Y=273|Color=8388608|FontID=1|IsHidden=T|Text=Surface Mount|Name=Mounting Technology
|RECORD=41|OwnerIndex=2074|IndexInSheet=5|OwnerPartId=-1|Location.X=1508|Location.Y=273|Color=8388608|FontID=1|IsHidden=T|Text=Yes|Name=REACH SVHC
|RECORD=41|OwnerIndex=2074|IndexInSheet=6|OwnerPartId=-1|Location.X=1508|Location.Y=273|Color=8388608|FontID=1|IsHidden=T|Text=4.7 KOhm|Name=Resistance
|RECORD=41|OwnerIndex=2074|IndexInSheet=7|OwnerPartId=-1|Location.X=1508|Location.Y=273|Color=8388608|FontID=1|IsHidden=T|Text=155 degC|Name=Max Operating Temperature
|RECORD=41|OwnerIndex=2074|IndexInSheet=8|OwnerPartId=-1|Location.X=1508|Location.Y=273|Color=8388608|FontID=1|IsHidden=T|Text=Manufacturer URL|Name=ComponentLink1Description
|RECORD=41|OwnerIndex=2074|IndexInSheet=9|OwnerPartId=-1|Location.X=1508|Location.Y=273|Color=8388608|FontID=1|IsHidden=T|Text=Datasheet|Name=ComponentLink2Description
|RECORD=41|OwnerIndex=2074|IndexInSheet=10|OwnerPartId=-1|Location.X=1508|Location.Y=273|Color=8388608|FontID=1|IsHidden=T|Text=2|Name=Pins
|RECORD=41|OwnerIndex=2074|IndexInSheet=11|OwnerPartId=-1|Location.X=1508|Location.Y=273|Color=8388608|FontID=1|IsHidden=T|Text=0402|Name=PackageReference
|RECORD=41|OwnerIndex=2074|IndexInSheet=12|OwnerPartId=-1|Location.X=1508|Location.Y=273|Color=8388608|FontID=1|IsHidden=T|Text=1%|Name=Tolerance
|RECORD=41|OwnerIndex=2074|IndexInSheet=13|OwnerPartId=-1|Location.X=1508|Location.Y=273|Color=8388608|FontID=1|IsHidden=T|Text=0402|Name=Case Code (Imperial)
|RECORD=41|OwnerIndex=2074|IndexInSheet=14|OwnerPartId=-1|Location.X=1508|Location.Y=273|Color=8388608|FontID=1|IsHidden=T|Text=1 mm|Name=Length
|RECORD=41|OwnerIndex=2074|IndexInSheet=15|OwnerPartId=-1|Location.X=1508|Location.Y=273|Color=8388608|FontID=1|IsHidden=T|Text=2-Pin Surface Mount Device, Body 1 x 0.5 mm|Name=PackageDescription
|RECORD=41|OwnerIndex=2074|IndexInSheet=16|OwnerPartId=-1|Location.X=1508|Location.Y=273|Color=8388608|FontID=1|IsHidden=T|Text=ERJ-2RKF4701X|Name=PartNumber
|RECORD=41|OwnerIndex=2074|IndexInSheet=17|OwnerPartId=-1|Location.X=1508|Location.Y=273|Color=8388608|FontID=1|IsHidden=T|Text=true|Name=RoHSCompliant
|RECORD=41|OwnerIndex=2074|IndexInSheet=18|OwnerPartId=-1|Location.X=1508|Location.Y=273|Color=8388608|FontID=1|IsHidden=T|Text=1|Name=Package Quantity
|RECORD=41|OwnerIndex=2074|IndexInSheet=19|OwnerPartId=-1|Location.X=1508|Location.Y=273|Color=8388608|FontID=1|IsHidden=T|Text=No|Name=Radiation Hardening
|RECORD=41|OwnerIndex=2074|IndexInSheet=20|OwnerPartId=-1|Location.X=1508|Location.Y=273|Color=8388608|FontID=1|IsHidden=T|Text=04/2015|Name=DatasheetVersion
|RECORD=41|OwnerIndex=2074|IndexInSheet=21|OwnerPartId=-1|Location.X=1508|Location.Y=273|Color=8388608|FontID=1|IsHidden=T|Text=0.5 mm|Name=Width
|RECORD=41|OwnerIndex=2074|IndexInSheet=22|OwnerPartId=-1|Location.X=1508|Location.Y=273|Color=8388608|FontID=1|IsHidden=T|Text=1005|Name=Case Code (Metric)
|RECORD=41|OwnerIndex=2074|IndexInSheet=23|OwnerPartId=-1|Location.X=1508|Location.Y=273|Color=8388608|FontID=1|IsHidden=T|Text=50 V|Name=Voltage Rating
|RECORD=41|OwnerIndex=2074|IndexInSheet=24|OwnerPartId=-1|Location.X=1508|Location.Y=273|Color=8388608|FontID=1|IsHidden=T|Text=0402|Name=Case\/Package
|RECORD=41|OwnerIndex=2074|IndexInSheet=25|OwnerPartId=-1|Location.X=1508|Location.Y=273|Color=8388608|FontID=1|IsHidden=T|Text=Surface Mount|Name=Mount
|RECORD=41|OwnerIndex=2074|IndexInSheet=26|OwnerPartId=-1|Location.X=1508|Location.Y=273|Color=8388608|FontID=3|IsHidden=T|Text=http://www.panasonic.com/|Name=ComponentLink1URL
|RECORD=41|OwnerIndex=2074|IndexInSheet=27|OwnerPartId=-1|Location.X=1508|Location.Y=273|Color=8388608|FontID=1|IsHidden=T|Text=-55 degC|Name=Min Operating Temperature
|RECORD=41|OwnerIndex=2074|IndexInSheet=28|OwnerPartId=-1|Location.X=1508|Location.Y=273|Color=8388608|FontID=1|IsHidden=T|Text=100 mW|Name=Power Rating
|RECORD=41|OwnerIndex=2074|IndexInSheet=29|OwnerPartId=-1|Location.X=1508|Location.Y=273|Color=8388608|FontID=1|IsHidden=T|Text=Cut Tape|Name=Packaging
|RECORD=41|OwnerIndex=2074|IndexInSheet=30|OwnerPartId=-1|Location.X=1508|Location.Y=273|Color=8388608|FontID=3|IsHidden=T|Text=http://industrial.panasonic.com/cdbs/www-data/pdf/RDA0000/AOA0000C86.pdf|Name=ComponentLink2URL
|RECORD=34|OwnerIndex=2074|IndexInSheet=-1|OwnerPartId=-1|Location.X=1519|Location.Y=273|Color=8388608|FontID=1|Text=R55|Name=Designator|ReadOnlyState=1
|RECORD=41|OwnerIndex=2074|IndexInSheet=-1|OwnerPartId=-1|Location.X=1519|Location.Y=257|Color=8388608|FontID=1|Text=4.7K_0402|Name=Comment
|RECORD=44|OwnerIndex=2074
|RECORD=45|OwnerIndex=2110|IndexInSheet=-1|Description=Chip Resistor, 2-Leads, Body 1.05x0.55mm, IPC High Density|UseComponentLibrary=T|ModelName=RESC1005X40X25LL05T05|ModelType=PCBLIB|DatafileCount=1|ModelDatafileEntity0=RESC1005X40X25LL05T05|ModelDatafileKind0=PCBLib|IsCurrent=T|DatalinksLocked=T|DatabaseDatalinksLocked=T
|RECORD=46|OwnerIndex=2111
|RECORD=48|OwnerIndex=2111
|RECORD=41|OwnerIndex=2113|IndexInSheet=-1|OwnerPartId=-1|Color=8388608|FontID=1|IsHidden=T|Text=2D|Name=Available Preview Images
|RECORD=45|OwnerIndex=2110|IndexInSheet=-1|Description=Chip Resistor, 2-Leads, Body 1.05x0.55mm, IPC Low Density|UseComponentLibrary=T|ModelName=RESC1005X40X25ML05T05|ModelType=PCBLIB|DatafileCount=1|ModelDatafileEntity0=RESC1005X40X25ML05T05|ModelDatafileKind0=PCBLib|DatalinksLocked=T|DatabaseDatalinksLocked=T
|RECORD=46|OwnerIndex=2115
|RECORD=48|OwnerIndex=2115
|RECORD=41|OwnerIndex=2117|IndexInSheet=-1|OwnerPartId=-1|Color=8388608|FontID=1|IsHidden=T|Text=2D|Name=Available Preview Images
|RECORD=45|OwnerIndex=2110|IndexInSheet=-1|Description=Chip Resistor, 2-Leads, Body 1.05x0.55mm, IPC Medium Density|UseComponentLibrary=T|ModelName=RESC1005X40X25NL05T05|ModelType=PCBLIB|DatafileCount=1|ModelDatafileEntity0=RESC1005X40X25NL05T05|ModelDatafileKind0=PCBLib|DatalinksLocked=T|DatabaseDatalinksLocked=T
|RECORD=46|OwnerIndex=2119
|RECORD=48|OwnerIndex=2119
|RECORD=41|OwnerIndex=2121|IndexInSheet=-1|OwnerPartId=-1|Color=8388608|FontID=1|IsHidden=T|Text=2D|Name=Available Preview Images
|RECORD=1|LibReference=b4654b650e69147ec39a6b967a45e02|ComponentDescription=None|PartCount=2|DisplayModeCount=1|IndexInSheet=196|OwnerPartId=-1|Location.X=1560|Location.Y=390|Orientation=1|CurrentPartId=1|LibraryPath=*|SourceLibraryName=Altium Content Vault|TargetFileName=*|AreaColor=11599871|Color=128|PartIDLocked=T|DesignItemId=CMP-14477-003537-2|AllPinCount=2
|RECORD=2|OwnerIndex=2123|OwnerPartId=1|Electrical=4|PinConglomerate=50|PinLength=7|Location.X=1567|Location.Y=390|Name=1|Designator=1|PinPropagationDelay=0.000000E+000
|RECORD=2|OwnerIndex=2123|OwnerPartId=1|Electrical=4|PinConglomerate=48|PinLength=6|Location.X=1574|Location.Y=390|Name=2|Designator=2|PinPropagationDelay=0.000000E+000
|RECORD=13|OwnerIndex=2123|IsNotAccesible=T|IndexInSheet=2|OwnerPartId=1|Location.X=1567|Location.Y=400|Corner.X=1567|Corner.Y=380|LineWidth=1|Color=16711680
|RECORD=13|OwnerIndex=2123|IsNotAccesible=T|IndexInSheet=3|OwnerPartId=1|Location.X=1573|Location.Y=400|Corner.X=1573|Corner.Y=380|LineWidth=1|Color=16711680
|RECORD=13|OwnerIndex=2123|IsNotAccesible=T|IndexInSheet=4|OwnerPartId=1|Location.X=1567|Location.Y=390|Corner.X=1564|Corner.Y=390|LineWidth=1|Color=16711680
|RECORD=13|OwnerIndex=2123|IsNotAccesible=T|IndexInSheet=5|OwnerPartId=1|Location.X=1574|Location.Y=390|Corner.X=1575|Corner.Y=390|LineWidth=1|Color=16711680
|RECORD=41|OwnerIndex=2123|IndexInSheet=6|OwnerPartId=-1|Location.X=1558|Location.Y=401|Color=8388608|FontID=1|IsHidden=T|Text=0.5mm|Name=Height
|RECORD=41|OwnerIndex=2123|IndexInSheet=7|OwnerPartId=-1|Location.X=1558|Location.Y=401|Color=8388608|FontID=1|IsHidden=T|Text=10000|Name=Package Quantity
|RECORD=41|OwnerIndex=2123|IndexInSheet=8|OwnerPartId=-1|Location.X=1558|Location.Y=401|Color=8388608|FontID=1|IsHidden=T|Text=M|Name=Series
|RECORD=41|OwnerIndex=2123|IndexInSheet=9|OwnerPartId=-1|Location.X=1558|Location.Y=401|Color=8388608|FontID=1|IsHidden=T|Text=85°C|Name=Max Operating Temperature
|RECORD=41|OwnerIndex=2123|IndexInSheet=10|OwnerPartId=-1|Location.X=1558|Location.Y=401|Color=8388608|FontID=1|IsHidden=T|Text=0.02inch|Name=Width
|RECORD=41|OwnerIndex=2123|IndexInSheet=11|OwnerPartId=-1|Location.X=1558|Location.Y=401|Color=8388608|FontID=1|IsHidden=T|Text=20%|Name=Tolerance
|RECORD=41|OwnerIndex=2123|IndexInSheet=12|OwnerPartId=-1|Location.X=1558|Location.Y=401|Color=8388608|FontID=1|IsHidden=T|Text=Surface Mount|Name=Mount
|RECORD=41|OwnerIndex=2123|IndexInSheet=13|OwnerPartId=-1|Location.X=1558|Location.Y=401|Color=8388608|FontID=1|IsHidden=T|Text=16V|Name=Voltage Rating (DC)
|RECORD=41|OwnerIndex=2123|IndexInSheet=14|OwnerPartId=-1|Location.X=1558|Location.Y=401|Color=8388608|FontID=1|IsHidden=T|Text=0.022inch|Name=Thickness
|RECORD=41|OwnerIndex=2123|IndexInSheet=15|OwnerPartId=-1|Location.X=1558|Location.Y=401|Color=8388608|FontID=1|IsHidden=T|Text=1mm|Name=Length
|RECORD=41|OwnerIndex=2123|IndexInSheet=16|OwnerPartId=-1|Location.X=1558|Location.Y=401|Color=8388608|FontID=1|IsHidden=T|Text=-55°C|Name=Min Operating Temperature
|RECORD=41|OwnerIndex=2123|IndexInSheet=17|OwnerPartId=-1|Location.X=1558|Location.Y=401|Color=8388608|FontID=1|IsHidden=T|Text=1uF|Name=Capacitance
|RECORD=41|OwnerIndex=2123|IndexInSheet=18|OwnerPartId=-1|Location.X=1558|Location.Y=401|Color=8388608|FontID=1|IsHidden=T|Text=X5R|Name=Dielectric
|RECORD=41|OwnerIndex=2123|IndexInSheet=19|OwnerPartId=-1|Location.X=1558|Location.Y=401|Color=8388608|FontID=1|IsHidden=T|Text=0.5mm|Name=Depth
|RECORD=41|OwnerIndex=2123|IndexInSheet=20|OwnerPartId=-1|Location.X=1558|Location.Y=401|Color=8388608|FontID=1|IsHidden=T|Text=Yes|Name=RoHS Compliant
|RECORD=41|OwnerIndex=2123|IndexInSheet=21|OwnerPartId=-1|Location.X=1558|Location.Y=401|Color=8388608|FontID=1|IsHidden=T|Text=Flat|Name=Construction
|RECORD=41|OwnerIndex=2123|IndexInSheet=22|OwnerPartId=-1|Location.X=1558|Location.Y=401|Color=8388608|FontID=1|IsHidden=T|Text=0402|Name=Case/Package
|RECORD=41|OwnerIndex=2123|IndexInSheet=23|OwnerPartId=-1|Location.X=1558|Location.Y=401|Color=8388608|FontID=1|IsHidden=T|Text=No|Name=Radiation Hardening
|RECORD=41|OwnerIndex=2123|IndexInSheet=24|OwnerPartId=-1|Location.X=1558|Location.Y=401|Color=8388608|FontID=1|IsHidden=T|Text=Tape and Reel|Name=Packaging
|RECORD=41|OwnerIndex=2123|IndexInSheet=25|OwnerPartId=-1|Location.X=1558|Location.Y=401|Color=8388608|FontID=1|IsHidden=T|Text=16V|Name=Voltage
|RECORD=41|OwnerIndex=2123|IndexInSheet=26|OwnerPartId=-1|Location.X=1558|Location.Y=401|Color=8388608|FontID=1|IsHidden=T|Text=16V|Name=Voltage Rating
|RECORD=41|OwnerIndex=2123|IndexInSheet=27|OwnerPartId=-1|Location.X=1558|Location.Y=401|Color=8388608|FontID=1|IsHidden=T|Text=Halogen Free|Name=Halogen Free
|RECORD=34|OwnerIndex=2123|IndexInSheet=-1|OwnerPartId=-1|Location.X=1563|Location.Y=401|Color=8388608|FontID=1|Text=C65|Name=Designator|ReadOnlyState=1
|RECORD=41|OwnerIndex=2123|IndexInSheet=-1|OwnerPartId=1|Location.X=1563|Location.Y=369|Color=8388608|FontID=1|Text=1uF_0402|Name=Comment
|RECORD=44|OwnerIndex=2123
|RECORD=45|OwnerIndex=2156|IndexInSheet=-1|UseComponentLibrary=T|ModelName=EMK105BJ105_V-F|ModelType=SIM|IsCurrent=T|DatalinksLocked=T|DatabaseDatalinksLocked=T
|RECORD=46|OwnerIndex=2157
|RECORD=48|OwnerIndex=2157
|RECORD=41|OwnerIndex=2159|IndexInSheet=-1|OwnerPartId=-1|Color=8388608|FontID=1|IsHidden=T|Text=General|Name=Kind
|RECORD=41|OwnerIndex=2159|IndexInSheet=-1|OwnerPartId=-1|Color=8388608|FontID=1|IsHidden=T|Text=Spice Subcircuit|Name=SubKind
|RECORD=41|OwnerIndex=2159|IndexInSheet=-1|OwnerPartId=-1|Color=8388608|FontID=1|IsHidden=T|Name=Spice Prefix
|RECORD=41|OwnerIndex=2159|IndexInSheet=-1|OwnerPartId=-1|Color=8388608|FontID=1|IsHidden=T|Name=Excluded Parts
|RECORD=41|OwnerIndex=2159|IndexInSheet=-1|OwnerPartId=-1|Color=8388608|FontID=1|IsHidden=T|Name=Netlist
|RECORD=41|OwnerIndex=2159|IndexInSheet=-1|OwnerPartId=-1|Color=8388608|FontID=1|IsHidden=T|Text=document_sim_cache\YSTRYKDD\0|Name=SimulationCacheLocation|ReadOnlyState=3
|RECORD=45|OwnerIndex=2156|IndexInSheet=-1|UseComponentLibrary=T|ModelName=FP-0402-L_1_0_0_05-W_0_5-IPC_C|ModelType=PCBLIB|DatafileCount=1|ModelDatafileEntity0=FP-0402-L_1_0_0_05-W_0_5-IPC_C|ModelDatafileKind0=PCBLib|IsCurrent=T|DatalinksLocked=T|DatabaseDatalinksLocked=T
|RECORD=46|OwnerIndex=2166
|RECORD=48|OwnerIndex=2166
|RECORD=45|OwnerIndex=2156|IndexInSheet=-1|UseComponentLibrary=T|ModelName=FP-0402-L_1_0_0_05-W_0_5-IPC_A|ModelType=PCBLIB|DatafileCount=1|ModelDatafileEntity0=FP-0402-L_1_0_0_05-W_0_5-IPC_A|ModelDatafileKind0=PCBLib|DatalinksLocked=T|DatabaseDatalinksLocked=T
|RECORD=46|OwnerIndex=2169
|RECORD=48|OwnerIndex=2169
|RECORD=45|OwnerIndex=2156|IndexInSheet=-1|UseComponentLibrary=T|ModelName=FP-0402-L_1_0_0_05-W_0_5-MFG|ModelType=PCBLIB|DatafileCount=1|ModelDatafileEntity0=FP-0402-L_1_0_0_05-W_0_5-MFG|ModelDatafileKind0=PCBLib|DatalinksLocked=T|DatabaseDatalinksLocked=T
|RECORD=46|OwnerIndex=2172
|RECORD=48|OwnerIndex=2172
|RECORD=45|OwnerIndex=2156|IndexInSheet=-1|UseComponentLibrary=T|ModelName=FP-0402-L_1_0_0_05-W_0_5-IPC_B|ModelType=PCBLIB|DatafileCount=1|ModelDatafileEntity0=FP-0402-L_1_0_0_05-W_0_5-IPC_B|ModelDatafileKind0=PCBLib|DatalinksLocked=T|DatabaseDatalinksLocked=T
|RECORD=46|OwnerIndex=2175
|RECORD=48|OwnerIndex=2175
|RECORD=1|LibReference=WE-CN-1P-M-R4|ComponentDescription=THT Vertical Pin Header WR-PHD, Pitch 2.54 mm, Single Row, 4 pins|PartCount=2|DisplayModeCount=1|IndexInSheet=197|OwnerPartId=-1|Location.X=440|Location.Y=310|IsMirrored=T|CurrentPartId=1|LibraryPath=*|SourceLibraryName=Altium Content Vault|TargetFileName=*|AreaColor=11599871|Color=128|PartIDLocked=T|DesignItemId=CMP-1502-01064-1|AllPinCount=4
|RECORD=2|OwnerIndex=2178|OwnerPartId=1|FormalType=1|Electrical=4|PinConglomerate=48|PinLength=20|Location.X=440|Location.Y=290|Name=2|Designator=2|PinPropagationDelay=0.000000E+000
|RECORD=2|OwnerIndex=2178|OwnerPartId=1|FormalType=1|Electrical=4|PinConglomerate=48|PinLength=20|Location.X=440|Location.Y=300|Name=1|Designator=1|PinPropagationDelay=0.000000E+000
|RECORD=6|OwnerIndex=2178|IsNotAccesible=T|IndexInSheet=2|OwnerPartId=1|LineWidth=1|Color=16711680|LocationCount=2|X1=440|Y1=290|X2=433|Y2=290
|RECORD=8|OwnerIndex=2178|IsNotAccesible=T|IndexInSheet=3|OwnerPartId=1|Location.X=430|Location.Y=290|Radius=3|SecondaryRadius=3|LineWidth=1|Color=16711680|AreaColor=16711680|IsSolid=T|Transparent=T
|RECORD=6|OwnerIndex=2178|IsNotAccesible=T|IndexInSheet=4|OwnerPartId=1|LineWidth=1|Color=16711680|LocationCount=2|X1=440|Y1=300|X2=433|Y2=300
|RECORD=14|OwnerIndex=2178|IsNotAccesible=T|IndexInSheet=5|OwnerPartId=1|Location.X=427|Location.Y=297|Corner.X=433|Corner.Y=303|Color=16711680|AreaColor=16711680|IsSolid=T
|RECORD=2|OwnerIndex=2178|OwnerPartId=1|FormalType=1|Electrical=4|PinConglomerate=48|PinLength=20|Location.X=440|Location.Y=280|Name=3|Designator=3|PinPropagationDelay=0.000000E+000
|RECORD=6|OwnerIndex=2178|IsNotAccesible=T|IndexInSheet=7|OwnerPartId=1|LineWidth=1|Color=16711680|LocationCount=2|X1=440|Y1=280|X2=433|Y2=280
|RECORD=8|OwnerIndex=2178|IsNotAccesible=T|IndexInSheet=8|OwnerPartId=1|Location.X=430|Location.Y=280|Radius=3|SecondaryRadius=3|LineWidth=1|Color=16711680|AreaColor=16711680|IsSolid=T|Transparent=T
|RECORD=2|OwnerIndex=2178|OwnerPartId=1|FormalType=1|Electrical=4|PinConglomerate=48|PinLength=20|Location.X=440|Location.Y=270|Name=4|Designator=4|PinPropagationDelay=0.000000E+000
|RECORD=6|OwnerIndex=2178|IsNotAccesible=T|IndexInSheet=10|OwnerPartId=1|LineWidth=1|Color=16711680|LocationCount=2|X1=440|Y1=270|X2=433|Y2=270
|RECORD=8|OwnerIndex=2178|IsNotAccesible=T|IndexInSheet=11|OwnerPartId=1|Location.X=430|Location.Y=270|Radius=3|SecondaryRadius=3|LineWidth=1|Color=16711680|AreaColor=16711680|IsSolid=T|Transparent=T
|RECORD=6|OwnerIndex=2178|IsNotAccesible=T|IndexInSheet=12|OwnerPartId=1|LineWidth=1|Color=16711680|LocationCount=5|X1=420|Y1=310|X2=440|Y2=310|X3=440|Y3=260|X4=420|Y4=260|X5=420|Y5=310
|RECORD=41|OwnerIndex=2178|IndexInSheet=13|OwnerPartId=-1|Location.X=419|Location.Y=311|Color=8388608|FontID=3|IsHidden=T|Text=http://www.we-online.de|Name=Manufacturer URL|IsMirrored=T
|RECORD=41|OwnerIndex=2178|IndexInSheet=14|OwnerPartId=-1|Location.X=419|Location.Y=311|Color=8388608|FontID=1|IsHidden=T|Text=500VAC|Name=Withstanding Voltage|IsMirrored=T
|RECORD=41|OwnerIndex=2178|IndexInSheet=15|OwnerPartId=-1|Location.X=419|Location.Y=311|Color=8388608|FontID=1|IsHidden=T|Text=-40to105degC|Name=Operating Temperature|IsMirrored=T
|RECORD=41|OwnerIndex=2178|IndexInSheet=16|OwnerPartId=-1|Location.X=419|Location.Y=311|Color=8388608|FontID=1|IsHidden=T|Text=Wurth Elektronik|Name=Manufacturer|IsMirrored=T
|RECORD=41|OwnerIndex=2178|IndexInSheet=17|OwnerPartId=-1|Location.X=419|Location.Y=311|Color=8388608|FontID=1|IsHidden=T|Text=3A|Name=Rated Current|IsMirrored=T
|RECORD=41|OwnerIndex=2178|IndexInSheet=18|OwnerPartId=-1|Location.X=419|Location.Y=311|Color=8388608|FontID=1|IsHidden=T|Text=250VAC|Name=Working Voltage|IsMirrored=T
|RECORD=41|OwnerIndex=2178|IndexInSheet=19|OwnerPartId=-1|Location.X=419|Location.Y=311|Color=8388608|FontID=1|IsHidden=T|Text=Bag|Name=Packaging|IsMirrored=T
|RECORD=41|OwnerIndex=2178|IndexInSheet=20|OwnerPartId=-1|Location.X=419|Location.Y=311|Color=8388608|FontID=1|IsHidden=T|Text=4|Name=Pin Number|IsMirrored=T
|RECORD=41|OwnerIndex=2178|IndexInSheet=21|OwnerPartId=-1|Location.X=419|Location.Y=311|Color=8388608|FontID=1|IsHidden=T|Text=THT|Name=Mounting Technology|IsMirrored=T
|RECORD=41|OwnerIndex=2178|IndexInSheet=22|OwnerPartId=-1|Location.X=419|Location.Y=311|Color=8388608|FontID=1|IsHidden=T|Text=61300411121|Name=Package Reference|IsMirrored=T
|RECORD=41|OwnerIndex=2178|IndexInSheet=23|OwnerPartId=-1|Location.X=419|Location.Y=311|Color=8388608|FontID=1|IsHidden=T|Text=Male|Name=Gender|IsMirrored=T
|RECORD=41|OwnerIndex=2178|IndexInSheet=24|OwnerPartId=-1|Location.X=419|Location.Y=311|Color=8388608|FontID=3|IsHidden=T|Text=https://katalog.we-online.de/em/datasheet/6130xx11121.pdf|Name=Datasheet URL|IsMirrored=T
|RECORD=41|OwnerIndex=2178|IndexInSheet=25|OwnerPartId=-1|Location.X=419|Location.Y=311|Color=8388608|FontID=1|IsHidden=T|Text=WurthElektronik|Name=Publisher|IsMirrored=T
|RECORD=41|OwnerIndex=2178|IndexInSheet=26|OwnerPartId=-1|Location.X=419|Location.Y=311|Color=8388608|FontID=1|IsHidden=T|Text=61300411121|Name=Part Number|IsMirrored=T
|RECORD=41|OwnerIndex=2178|IndexInSheet=27|OwnerPartId=-1|Location.X=419|Location.Y=311|Color=8388608|FontID=1|IsHidden=T|Text=Single|Name=Row Number|IsMirrored=T
|RECORD=41|OwnerIndex=2178|IndexInSheet=28|OwnerPartId=-1|Location.X=419|Location.Y=311|Color=8388608|FontID=1|IsHidden=T|Text=20mOhm|Name=Contact Resistance|IsMirrored=T
|RECORD=41|OwnerIndex=2178|IndexInSheet=29|OwnerPartId=-1|Location.X=419|Location.Y=311|Color=8388608|FontID=1|IsHidden=T|Text=2.54mm|Name=Pitch|IsMirrored=T
|RECORD=41|OwnerIndex=2178|IndexInSheet=30|OwnerPartId=-1|Location.X=419|Location.Y=311|Color=8388608|FontID=1|IsHidden=T|Text=Vertical|Name=Orientation|IsMirrored=T
|RECORD=34|OwnerIndex=2178|IndexInSheet=-1|OwnerPartId=-1|Location.X=419|Location.Y=311|Color=8388608|FontID=1|Text=P5|Name=Designator|ReadOnlyState=1|IsMirrored=T
|RECORD=41|OwnerIndex=2178|IndexInSheet=-1|OwnerPartId=-1|Location.X=419|Location.Y=251|Color=8388608|FontID=10|Text=61300411121|Name=Comment|ReadOnlyState=1|IsMirrored=T
|RECORD=44|OwnerIndex=2178
|RECORD=45|OwnerIndex=2216|IndexInSheet=-1|Description=Pin Header, pitch 2.54 mm, THT, Vertical, single row, 4p|UseComponentLibrary=T|ModelName=61300411121|ModelType=PCBLIB|DatafileCount=1|ModelDatafileEntity0=61300411121|ModelDatafileKind0=PCBLib|IsCurrent=T|DatalinksLocked=T|DatabaseDatalinksLocked=T
|RECORD=46|OwnerIndex=2217
|RECORD=48|OwnerIndex=2217
|RECORD=41|OwnerIndex=2219|IndexInSheet=-1|OwnerPartId=-1|Color=8388608|FontID=1|IsHidden=T|Text=2D|Name=Available Preview Images
|RECORD=17|IndexInSheet=198|OwnerPartId=-1|ShowNetName=T|Location.X=490|Location.Y=320|Orientation=1|Color=128|FontID=1|Text=+3.3V
|RECORD=17|IndexInSheet=199|OwnerPartId=-1|ShowNetName=T|Location.X=530|Location.Y=280|Color=255|FontID=1|Text=DC_I2C_SCL|IsCrossSheetConnector=T
|RECORD=17|IndexInSheet=200|OwnerPartId=-1|ShowNetName=T|Location.X=530|Location.Y=270|Color=255|FontID=1|Text=DC_I2C_SDA|IsCrossSheetConnector=T
|RECORD=17|IndexInSheet=201|OwnerPartId=-1|Style=4|ShowNetName=T|Location.X=490|Location.Y=250|Orientation=3|Color=128|FontID=1|Text=GND
|RECORD=1|LibReference=c23a69dc6c9e2f18f2079038eb95dd1|ComponentDescription=Crystal 32.768kHz ±20ppm (Tol) 12.5pF FUND 70k? 2-Pin CSMD T/R|PartCount=2|DisplayModeCount=1|IndexInSheet=202|OwnerPartId=-1|Location.X=1390|Location.Y=540|Orientation=2|CurrentPartId=1|LibraryPath=*|SourceLibraryName=Altium Content Vault|TargetFileName=*|AreaColor=11599871|Color=128|PartIDLocked=T|DesignItemId=CMP-0447-00001-4|AllPinCount=2
|RECORD=2|OwnerIndex=2225|OwnerPartId=1|Electrical=4|PinConglomerate=48|PinLength=5|Location.X=1385|Location.Y=540|Name=1|Designator=1|PinPropagationDelay=0.000000E+000
|RECORD=2|OwnerIndex=2225|OwnerPartId=1|Electrical=4|PinConglomerate=50|PinLength=5|Location.X=1365|Location.Y=540|Name=2|Designator=2|PinPropagationDelay=0.000000E+000
|RECORD=13|OwnerIndex=2225|IsNotAccesible=T|IndexInSheet=2|OwnerPartId=1|Location.X=1385|Location.Y=532|Corner.X=1385|Corner.Y=548|LineWidth=1|Color=16711680
|RECORD=13|OwnerIndex=2225|IsNotAccesible=T|IndexInSheet=3|OwnerPartId=1|Location.X=1365|Location.Y=532|Corner.X=1365|Corner.Y=548|LineWidth=1|Color=16711680
|RECORD=13|OwnerIndex=2225|IsNotAccesible=T|IndexInSheet=4|OwnerPartId=1|Location.X=1380|Location.Y=530|Corner.X=1380|Corner.Y=550|LineWidth=1|Color=16711680
|RECORD=13|OwnerIndex=2225|IsNotAccesible=T|IndexInSheet=5|OwnerPartId=1|Location.X=1380|Location.Y=530|Corner.X=1370|Corner.Y=530|LineWidth=1|Color=16711680
|RECORD=13|OwnerIndex=2225|IsNotAccesible=T|IndexInSheet=6|OwnerPartId=1|Location.X=1370|Location.Y=530|Corner.X=1370|Corner.Y=550|LineWidth=1|Color=16711680
|RECORD=13|OwnerIndex=2225|IsNotAccesible=T|IndexInSheet=7|OwnerPartId=1|Location.X=1370|Location.Y=550|Corner.X=1380|Corner.Y=550|LineWidth=1|Color=16711680
|RECORD=13|OwnerIndex=2225|IsNotAccesible=T|IndexInSheet=8|OwnerPartId=1|Location.X=1385|Location.Y=540|Corner.X=1387|Corner.Y=540|LineWidth=1|Color=16711680
|RECORD=13|OwnerIndex=2225|IsNotAccesible=T|IndexInSheet=9|OwnerPartId=1|Location.X=1365|Location.Y=540|Corner.X=1364|Corner.Y=540|LineWidth=1|Color=16711680
|RECORD=41|OwnerIndex=2225|IndexInSheet=10|OwnerPartId=-1|Location.X=1358|Location.Y=551|Color=8388608|FontID=1|IsHidden=T|Text=No|Name=Radiation Hardening
|RECORD=41|OwnerIndex=2225|IndexInSheet=11|OwnerPartId=-1|Location.X=1358|Location.Y=551|Color=8388608|FontID=1|IsHidden=T|Text=32.768kHz|Name=Frequency
|RECORD=41|OwnerIndex=2225|IndexInSheet=12|OwnerPartId=-1|Location.X=1358|Location.Y=551|Color=8388608|FontID=1|IsHidden=T|Text=3.2mm|Name=Length
|RECORD=41|OwnerIndex=2225|IndexInSheet=13|OwnerPartId=-1|Location.X=1358|Location.Y=551|Color=8388608|FontID=1|IsHidden=T|Text=85°C|Name=Max Operating Temperature
|RECORD=41|OwnerIndex=2225|IndexInSheet=14|OwnerPartId=-1|Location.X=1358|Location.Y=551|Color=8388608|FontID=1|IsHidden=T|Text=2|Name=Number of Pins
|RECORD=41|OwnerIndex=2225|IndexInSheet=15|OwnerPartId=-1|Location.X=1358|Location.Y=551|Color=8388608|FontID=1|IsHidden=T|Text=70kR|Name=ESR (Equivalent Series Resistance)
|RECORD=41|OwnerIndex=2225|IndexInSheet=16|OwnerPartId=-1|Location.X=1358|Location.Y=551|Color=8388608|FontID=1|IsHidden=T|Text=ABS07|Name=Series
|RECORD=41|OwnerIndex=2225|IndexInSheet=17|OwnerPartId=-1|Location.X=1358|Location.Y=551|Color=8388608|FontID=1|IsHidden=T|Text=-40°C|Name=Min Operating Temperature
|RECORD=41|OwnerIndex=2225|IndexInSheet=18|OwnerPartId=-1|Location.X=1358|Location.Y=551|Color=8388608|FontID=1|IsHidden=T|Text=20ppm|Name=Frequency Tolerance
|RECORD=41|OwnerIndex=2225|IndexInSheet=19|OwnerPartId=-1|Location.X=1358|Location.Y=551|Color=8388608|FontID=1|IsHidden=T|Text=Tape and Reel|Name=Packaging
|RECORD=41|OwnerIndex=2225|IndexInSheet=20|OwnerPartId=-1|Location.X=1358|Location.Y=551|Color=8388608|FontID=1|IsHidden=T|Text=0.9mm|Name=Height
|RECORD=41|OwnerIndex=2225|IndexInSheet=21|OwnerPartId=-1|Location.X=1358|Location.Y=551|Color=8388608|FontID=1|IsHidden=T|Text=1.5mm|Name=Width
|RECORD=41|OwnerIndex=2225|IndexInSheet=22|OwnerPartId=-1|Location.X=1358|Location.Y=551|Color=8388608|FontID=1|IsHidden=T|Text=1.5mm|Name=Depth
|RECORD=41|OwnerIndex=2225|IndexInSheet=23|OwnerPartId=-1|Location.X=1358|Location.Y=551|Color=8388608|FontID=1|IsHidden=T|Text=12.5pF|Name=Load Capacitance
|RECORD=41|OwnerIndex=2225|IndexInSheet=24|OwnerPartId=-1|Location.X=1358|Location.Y=551|Color=8388608|FontID=1|IsHidden=T|Text=Yes|Name=RoHS Compliant
|RECORD=41|OwnerIndex=2225|IndexInSheet=25|OwnerPartId=-1|Location.X=1358|Location.Y=551|Color=8388608|FontID=1|IsHidden=T|Text=20ppm|Name=Tolerance
|RECORD=41|OwnerIndex=2225|IndexInSheet=26|OwnerPartId=-1|Location.X=1358|Location.Y=551|Color=8388608|FontID=1|IsHidden=T|Text=SMD/SMT|Name=Termination
|RECORD=41|OwnerIndex=2225|IndexInSheet=27|OwnerPartId=-1|Location.X=1358|Location.Y=551|Color=8388608|FontID=1|IsHidden=T|Text=Lead Free|Name=Lead Free
|RECORD=41|OwnerIndex=2225|IndexInSheet=28|OwnerPartId=-1|Location.X=1358|Location.Y=551|Color=8388608|FontID=1|IsHidden=T|Text=70kR|Name=Series Resistance
|RECORD=41|OwnerIndex=2225|IndexInSheet=29|OwnerPartId=-1|Location.X=1358|Location.Y=551|Color=8388608|FontID=1|IsHidden=T|Text=No SVHC|Name=REACH SVHC
|RECORD=41|OwnerIndex=2225|IndexInSheet=30|OwnerPartId=-1|Location.X=1358|Location.Y=551|Color=8388608|FontID=1|IsHidden=T|Text=CSMD|Name=Case/Package
|RECORD=41|OwnerIndex=2225|IndexInSheet=31|OwnerPartId=-1|Location.X=1358|Location.Y=551|Color=8388608|FontID=1|IsHidden=T|Text=32.768 kHz|Name=Operating Frequency
|RECORD=41|OwnerIndex=2225|IndexInSheet=32|OwnerPartId=-1|Location.X=1358|Location.Y=551|Color=8388608|FontID=1|IsHidden=T|Text=3000|Name=Package Quantity
|RECORD=34|OwnerIndex=2225|IndexInSheet=-1|OwnerPartId=-1|Location.X=1363|Location.Y=551|Color=8388608|FontID=1|Text=Y1|Name=Designator|ReadOnlyState=1
|RECORD=41|OwnerIndex=2225|IndexInSheet=-1|OwnerPartId=1|Location.X=1363|Location.Y=519|Color=8388608|FontID=1|Text=ABS07-32.768KHZ-T|Name=Comment
|RECORD=44|OwnerIndex=2225
|RECORD=45|OwnerIndex=2263|IndexInSheet=-1|UseComponentLibrary=T|ModelName=FP-ABS07-MFG|ModelType=PCBLIB|DatafileCount=1|ModelDatafileEntity0=FP-ABS07-MFG|ModelDatafileKind0=PCBLib|IsCurrent=T|DatalinksLocked=T|DatabaseDatalinksLocked=T
|RECORD=46|OwnerIndex=2264
|RECORD=48|OwnerIndex=2264
|RECORD=1|LibReference=CAP-NP-2|ComponentDescription=Chip Capacitor, 22 pF, +/- 5%, 50 V, -55 to 125 degC, 0402 (1005 Metric), RoHS, Tape and Reel|PartCount=2|DisplayModeCount=1|IndexInSheet=203|OwnerPartId=-1|Location.X=1420|Location.Y=470|Orientation=1|CurrentPartId=1|LibraryPath=*|SourceLibraryName=Altium Content Vault|TargetFileName=*|AreaColor=11599871|Color=128|PartIDLocked=T|DesignItemId=CMP-2100-03590-1|AllPinCount=2
|RECORD=2|OwnerIndex=2267|OwnerPartId=1|FormalType=1|Electrical=4|PinConglomerate=35|PinLength=10|Location.X=1420|Location.Y=480|Name=1|Designator=1|SwapIDPart=0|PinPropagationDelay=0.000000E+000
|RECORD=2|OwnerIndex=2267|OwnerPartId=1|FormalType=1|Electrical=4|PinConglomerate=33|PinLength=10|Location.X=1420|Location.Y=490|Name=2|Designator=2|SwapIDPart=0|PinPropagationDelay=0.000000E+000
|RECORD=13|OwnerIndex=2267|IsNotAccesible=T|IndexInSheet=2|OwnerPartId=1|Location.X=1412|Location.Y=487|Corner.X=1428|Corner.Y=487|LineWidth=1|Color=16711680
|RECORD=13|OwnerIndex=2267|IsNotAccesible=T|IndexInSheet=3|OwnerPartId=1|Location.X=1428|Location.Y=483|Corner.X=1412|Corner.Y=483|LineWidth=1|Color=16711680
|RECORD=6|OwnerIndex=2267|IsNotAccesible=T|IndexInSheet=4|OwnerPartId=1|LineWidth=1|Color=16711680|LocationCount=2|X1=1420|Y1=480|X2=1420|Y2=483
|RECORD=6|OwnerIndex=2267|IsNotAccesible=T|IndexInSheet=5|OwnerPartId=1|LineWidth=1|Color=16711680|LocationCount=2|X1=1420|Y1=490|X2=1420|Y2=487
|RECORD=41|OwnerIndex=2267|IndexInSheet=6|OwnerPartId=-1|Location.X=1411|Location.Y=502|Color=8388608|FontID=3|IsHidden=T|Text=http://www.yageo.com/NewPortal/yageodocoutput?fileName=/pdf/MLCC/UPY-GP_NP0_16V-to-50V_14.pdf|Name=Datasheet URL
|RECORD=41|OwnerIndex=2267|IndexInSheet=7|OwnerPartId=-1|Location.X=1411|Location.Y=502|Color=8388608|FontID=1|IsHidden=T|Text=0.5mm|Name=Depth
|RECORD=41|OwnerIndex=2267|IndexInSheet=8|OwnerPartId=-1|Location.X=1411|Location.Y=502|Color=8388608|FontID=1|IsHidden=T|Text=50V|Name=Voltage Rating
|RECORD=41|OwnerIndex=2267|IndexInSheet=9|OwnerPartId=-1|Location.X=1411|Location.Y=502|Color=8388608|FontID=1|IsHidden=T|Text=2|Name=Number of Pins
|RECORD=41|OwnerIndex=2267|IndexInSheet=10|OwnerPartId=-1|Location.X=1411|Location.Y=502|Color=8388608|FontID=1|IsHidden=T|Text=0.5mm|Name=Height
|RECORD=41|OwnerIndex=2267|IndexInSheet=11|OwnerPartId=-1|Location.X=1411|Location.Y=502|Color=8388608|FontID=1|IsHidden=T|Text=-55degC|Name=Min Operating Temperature
|RECORD=41|OwnerIndex=2267|IndexInSheet=12|OwnerPartId=-1|Location.X=1411|Location.Y=502|Color=8388608|FontID=1|IsHidden=T|Text=NoSVHC|Name=REACH SVHC
|RECORD=41|OwnerIndex=2267|IndexInSheet=13|OwnerPartId=-1|Location.X=1411|Location.Y=502|Color=8388608|FontID=1|IsHidden=T|Text=Ceramic|Name=Dielectric Material
|RECORD=41|OwnerIndex=2267|IndexInSheet=14|OwnerPartId=-1|Location.X=1411|Location.Y=502|Color=8388608|FontID=1|IsHidden=T|Text=22pF|Name=Capacitance
|RECORD=41|OwnerIndex=2267|IndexInSheet=15|OwnerPartId=-1|Location.X=1411|Location.Y=502|Color=8388608|FontID=1|IsHidden=T|Text=125degC|Name=Max Operating Temperature
|RECORD=41|OwnerIndex=2267|IndexInSheet=16|OwnerPartId=-1|Location.X=1411|Location.Y=502|Color=8388608|FontID=1|IsHidden=T|Text=50V|Name=Voltage Rating (DC)
|RECORD=41|OwnerIndex=2267|IndexInSheet=17|OwnerPartId=-1|Location.X=1411|Location.Y=502|Color=8388608|FontID=1|IsHidden=T|Text=Ceramic|Name=Composition
|RECORD=41|OwnerIndex=2267|IndexInSheet=18|OwnerPartId=-1|Location.X=1411|Location.Y=502|Color=8388608|FontID=1|IsHidden=T|Text=TapeandReel|Name=Packaging
|RECORD=41|OwnerIndex=2267|IndexInSheet=19|OwnerPartId=-1|Location.X=1411|Location.Y=502|Color=8388608|FontID=1|IsHidden=T|Text=1|Name=Package Quantity
|RECORD=41|OwnerIndex=2267|IndexInSheet=20|OwnerPartId=-1|Location.X=1411|Location.Y=502|Color=8388608|FontID=1|IsHidden=T|Text=0402|Name=Package Reference
|RECORD=41|OwnerIndex=2267|IndexInSheet=21|OwnerPartId=-1|Location.X=1411|Location.Y=502|Color=8388608|FontID=1|IsHidden=T|Text=30ppm/degC|Name=Temperature Coefficient
|RECORD=41|OwnerIndex=2267|IndexInSheet=22|OwnerPartId=-1|Location.X=1411|Location.Y=502|Color=8388608|FontID=1|IsHidden=T|Text=C0G|Name=Dielectric
|RECORD=41|OwnerIndex=2267|IndexInSheet=23|OwnerPartId=-1|Location.X=1411|Location.Y=502|Color=8388608|FontID=1|IsHidden=T|Text=1mm|Name=Length
|RECORD=41|OwnerIndex=2267|IndexInSheet=24|OwnerPartId=-1|Location.X=1411|Location.Y=502|Color=8388608|FontID=1|IsHidden=T|Text=No|Name=Radiation Hardening
|RECORD=41|OwnerIndex=2267|IndexInSheet=25|OwnerPartId=-1|Location.X=1411|Location.Y=502|Color=8388608|FontID=1|IsHidden=T|Text=2-Pin Surface Mount Device, Body 1 x 0.5 mm|Name=Package Description
|RECORD=41|OwnerIndex=2267|IndexInSheet=26|OwnerPartId=-1|Location.X=1411|Location.Y=502|Color=8388608|FontID=1|IsHidden=T|Text=True|Name=RoHSCompliant
|RECORD=41|OwnerIndex=2267|IndexInSheet=27|OwnerPartId=-1|Location.X=1411|Location.Y=502|Color=8388608|FontID=1|IsHidden=T|Text=0.022inch|Name=Thickness
|RECORD=41|OwnerIndex=2267|IndexInSheet=28|OwnerPartId=-1|Location.X=1411|Location.Y=502|Color=8388608|FontID=1|IsHidden=T|Text=Yageo|Name=Manufacturer
|RECORD=41|OwnerIndex=2267|IndexInSheet=29|OwnerPartId=-1|Location.X=1411|Location.Y=502|Color=8388608|FontID=3|IsHidden=T|Text=http://www.yageo.com/|Name=Manufacturer URL
|RECORD=41|OwnerIndex=2267|IndexInSheet=30|OwnerPartId=-1|Location.X=1411|Location.Y=502|Color=8388608|FontID=1|IsHidden=T|Text=SurfaceMount|Name=Mount
|RECORD=41|OwnerIndex=2267|IndexInSheet=31|OwnerPartId=-1|Location.X=1411|Location.Y=502|Color=8388608|FontID=1|IsHidden=T|Text=1005|Name=Case Code (Metric)
|RECORD=41|OwnerIndex=2267|IndexInSheet=32|OwnerPartId=-1|Location.X=1411|Location.Y=502|Color=8388608|FontID=1|IsHidden=T|Text=100GR|Name=Insulation Resistance
|RECORD=41|OwnerIndex=2267|IndexInSheet=33|OwnerPartId=-1|Location.X=1411|Location.Y=502|Color=8388608|FontID=1|IsHidden=T|Text=0402|Name=Case/Package
|RECORD=41|OwnerIndex=2267|IndexInSheet=34|OwnerPartId=-1|Location.X=1411|Location.Y=502|Color=8388608|FontID=1|IsHidden=T|Text=5%|Name=Tolerance
|RECORD=41|OwnerIndex=2267|IndexInSheet=35|OwnerPartId=-1|Location.X=1411|Location.Y=502|Color=8388608|FontID=1|IsHidden=T|Text=SMD/SMT|Name=Termination
|RECORD=41|OwnerIndex=2267|IndexInSheet=36|OwnerPartId=-1|Location.X=1411|Location.Y=502|Color=8388608|FontID=1|IsHidden=T|Text=0.02inch|Name=Width
|RECORD=41|OwnerIndex=2267|IndexInSheet=37|OwnerPartId=-1|Location.X=1411|Location.Y=502|Color=8388608|FontID=1|IsHidden=T|Text=Rev. 14, 07/2016|Name=Datasheet Version
|RECORD=41|OwnerIndex=2267|IndexInSheet=38|OwnerPartId=-1|Location.X=1411|Location.Y=502|Color=8388608|FontID=1|IsHidden=T|Text=LeadFree|Name=Lead Free
|RECORD=41|OwnerIndex=2267|IndexInSheet=39|OwnerPartId=-1|Location.X=1411|Location.Y=502|Color=8388608|FontID=1|IsHidden=T|Text=0402|Name=Case Code (Imperial)
|RECORD=34|OwnerIndex=2267|IndexInSheet=-1|OwnerPartId=-1|Location.X=1429|Location.Y=481|Color=8388608|FontID=1|Text=C68|Name=Designator|ReadOnlyState=1
|RECORD=41|OwnerIndex=2267|IndexInSheet=-1|OwnerPartId=-1|Location.X=1429|Location.Y=471|Color=8388608|FontID=1|Text=22pF_50V_0402|Name=Comment
|RECORD=44|OwnerIndex=2267
|RECORD=45|OwnerIndex=2312|IndexInSheet=-1|Description=Chip Capacitor, 2-Leads, Body 1.00x0.50mm, IPC Low Density|UseComponentLibrary=T|ModelName=CAPC1005X55X25ML05T05|ModelType=PCBLIB|DatafileCount=1|ModelDatafileEntity0=CAPC1005X55X25ML05T05|ModelDatafileKind0=PCBLib|IsCurrent=T|DatalinksLocked=T|DatabaseDatalinksLocked=T
|RECORD=46|OwnerIndex=2313
|RECORD=48|OwnerIndex=2313
|RECORD=41|OwnerIndex=2315|IndexInSheet=-1|OwnerPartId=-1|Color=8388608|FontID=1|IsHidden=T|Text=2D|Name=Available Preview Images
|RECORD=45|OwnerIndex=2312|IndexInSheet=-1|Description=Chip Capacitor, 2-Leads, Body 1.00x0.50mm, IPC Medium Density|UseComponentLibrary=T|ModelName=CAPC1005X55X25NL05T05|ModelType=PCBLIB|DatafileCount=1|ModelDatafileEntity0=CAPC1005X55X25NL05T05|ModelDatafileKind0=PCBLib|DatalinksLocked=T|DatabaseDatalinksLocked=T
|RECORD=46|OwnerIndex=2317
|RECORD=48|OwnerIndex=2317
|RECORD=41|OwnerIndex=2319|IndexInSheet=-1|OwnerPartId=-1|Color=8388608|FontID=1|IsHidden=T|Text=2D|Name=Available Preview Images
|RECORD=45|OwnerIndex=2312|IndexInSheet=-1|Description=Chip Capacitor, 2-Leads, Body 1.00x0.50mm, IPC High Density|UseComponentLibrary=T|ModelName=CAPC1005X55X25LL05T05|ModelType=PCBLIB|DatafileCount=1|ModelDatafileEntity0=CAPC1005X55X25LL05T05|ModelDatafileKind0=PCBLib|DatalinksLocked=T|DatabaseDatalinksLocked=T
|RECORD=46|OwnerIndex=2321
|RECORD=48|OwnerIndex=2321
|RECORD=41|OwnerIndex=2323|IndexInSheet=-1|OwnerPartId=-1|Color=8388608|FontID=1|IsHidden=T|Text=2D|Name=Available Preview Images
|RECORD=1|LibReference=CAP-NP-2|ComponentDescription=Chip Capacitor, 22 pF, +/- 5%, 50 V, -55 to 125 degC, 0402 (1005 Metric), RoHS, Tape and Reel|PartCount=2|DisplayModeCount=1|IndexInSheet=204|OwnerPartId=-1|Location.X=1340|Location.Y=470|Orientation=1|CurrentPartId=1|LibraryPath=*|SourceLibraryName=Altium Content Vault|TargetFileName=*|AreaColor=11599871|Color=128|PartIDLocked=T|DesignItemId=CMP-2100-03590-1|AllPinCount=2
|RECORD=2|OwnerIndex=2325|OwnerPartId=1|FormalType=1|Electrical=4|PinConglomerate=35|PinLength=10|Location.X=1340|Location.Y=480|Name=1|Designator=1|SwapIDPart=0|PinPropagationDelay=0.000000E+000
|RECORD=2|OwnerIndex=2325|OwnerPartId=1|FormalType=1|Electrical=4|PinConglomerate=33|PinLength=10|Location.X=1340|Location.Y=490|Name=2|Designator=2|SwapIDPart=0|PinPropagationDelay=0.000000E+000
|RECORD=13|OwnerIndex=2325|IsNotAccesible=T|IndexInSheet=2|OwnerPartId=1|Location.X=1332|Location.Y=487|Corner.X=1348|Corner.Y=487|LineWidth=1|Color=16711680
|RECORD=13|OwnerIndex=2325|IsNotAccesible=T|IndexInSheet=3|OwnerPartId=1|Location.X=1348|Location.Y=483|Corner.X=1332|Corner.Y=483|LineWidth=1|Color=16711680
|RECORD=6|OwnerIndex=2325|IsNotAccesible=T|IndexInSheet=4|OwnerPartId=1|LineWidth=1|Color=16711680|LocationCount=2|X1=1340|Y1=480|X2=1340|Y2=483
|RECORD=6|OwnerIndex=2325|IsNotAccesible=T|IndexInSheet=5|OwnerPartId=1|LineWidth=1|Color=16711680|LocationCount=2|X1=1340|Y1=490|X2=1340|Y2=487
|RECORD=41|OwnerIndex=2325|IndexInSheet=6|OwnerPartId=-1|Location.X=1331|Location.Y=502|Color=8388608|FontID=3|IsHidden=T|Text=http://www.yageo.com/NewPortal/yageodocoutput?fileName=/pdf/MLCC/UPY-GP_NP0_16V-to-50V_14.pdf|Name=Datasheet URL
|RECORD=41|OwnerIndex=2325|IndexInSheet=7|OwnerPartId=-1|Location.X=1331|Location.Y=502|Color=8388608|FontID=1|IsHidden=T|Text=0.5mm|Name=Depth
|RECORD=41|OwnerIndex=2325|IndexInSheet=8|OwnerPartId=-1|Location.X=1331|Location.Y=502|Color=8388608|FontID=1|IsHidden=T|Text=50V|Name=Voltage Rating
|RECORD=41|OwnerIndex=2325|IndexInSheet=9|OwnerPartId=-1|Location.X=1331|Location.Y=502|Color=8388608|FontID=1|IsHidden=T|Text=2|Name=Number of Pins
|RECORD=41|OwnerIndex=2325|IndexInSheet=10|OwnerPartId=-1|Location.X=1331|Location.Y=502|Color=8388608|FontID=1|IsHidden=T|Text=0.5mm|Name=Height
|RECORD=41|OwnerIndex=2325|IndexInSheet=11|OwnerPartId=-1|Location.X=1331|Location.Y=502|Color=8388608|FontID=1|IsHidden=T|Text=-55degC|Name=Min Operating Temperature
|RECORD=41|OwnerIndex=2325|IndexInSheet=12|OwnerPartId=-1|Location.X=1331|Location.Y=502|Color=8388608|FontID=1|IsHidden=T|Text=NoSVHC|Name=REACH SVHC
|RECORD=41|OwnerIndex=2325|IndexInSheet=13|OwnerPartId=-1|Location.X=1331|Location.Y=502|Color=8388608|FontID=1|IsHidden=T|Text=Ceramic|Name=Dielectric Material
|RECORD=41|OwnerIndex=2325|IndexInSheet=14|OwnerPartId=-1|Location.X=1331|Location.Y=502|Color=8388608|FontID=1|IsHidden=T|Text=22pF|Name=Capacitance
|RECORD=41|OwnerIndex=2325|IndexInSheet=15|OwnerPartId=-1|Location.X=1331|Location.Y=502|Color=8388608|FontID=1|IsHidden=T|Text=125degC|Name=Max Operating Temperature
|RECORD=41|OwnerIndex=2325|IndexInSheet=16|OwnerPartId=-1|Location.X=1331|Location.Y=502|Color=8388608|FontID=1|IsHidden=T|Text=50V|Name=Voltage Rating (DC)
|RECORD=41|OwnerIndex=2325|IndexInSheet=17|OwnerPartId=-1|Location.X=1331|Location.Y=502|Color=8388608|FontID=1|IsHidden=T|Text=Ceramic|Name=Composition
|RECORD=41|OwnerIndex=2325|IndexInSheet=18|OwnerPartId=-1|Location.X=1331|Location.Y=502|Color=8388608|FontID=1|IsHidden=T|Text=TapeandReel|Name=Packaging
|RECORD=41|OwnerIndex=2325|IndexInSheet=19|OwnerPartId=-1|Location.X=1331|Location.Y=502|Color=8388608|FontID=1|IsHidden=T|Text=1|Name=Package Quantity
|RECORD=41|OwnerIndex=2325|IndexInSheet=20|OwnerPartId=-1|Location.X=1331|Location.Y=502|Color=8388608|FontID=1|IsHidden=T|Text=0402|Name=Package Reference
|RECORD=41|OwnerIndex=2325|IndexInSheet=21|OwnerPartId=-1|Location.X=1331|Location.Y=502|Color=8388608|FontID=1|IsHidden=T|Text=30ppm/degC|Name=Temperature Coefficient
|RECORD=41|OwnerIndex=2325|IndexInSheet=22|OwnerPartId=-1|Location.X=1331|Location.Y=502|Color=8388608|FontID=1|IsHidden=T|Text=C0G|Name=Dielectric
|RECORD=41|OwnerIndex=2325|IndexInSheet=23|OwnerPartId=-1|Location.X=1331|Location.Y=502|Color=8388608|FontID=1|IsHidden=T|Text=1mm|Name=Length
|RECORD=41|OwnerIndex=2325|IndexInSheet=24|OwnerPartId=-1|Location.X=1331|Location.Y=502|Color=8388608|FontID=1|IsHidden=T|Text=No|Name=Radiation Hardening
|RECORD=41|OwnerIndex=2325|IndexInSheet=25|OwnerPartId=-1|Location.X=1331|Location.Y=502|Color=8388608|FontID=1|IsHidden=T|Text=2-Pin Surface Mount Device, Body 1 x 0.5 mm|Name=Package Description
|RECORD=41|OwnerIndex=2325|IndexInSheet=26|OwnerPartId=-1|Location.X=1331|Location.Y=502|Color=8388608|FontID=1|IsHidden=T|Text=True|Name=RoHSCompliant
|RECORD=41|OwnerIndex=2325|IndexInSheet=27|OwnerPartId=-1|Location.X=1331|Location.Y=502|Color=8388608|FontID=1|IsHidden=T|Text=0.022inch|Name=Thickness
|RECORD=41|OwnerIndex=2325|IndexInSheet=28|OwnerPartId=-1|Location.X=1331|Location.Y=502|Color=8388608|FontID=1|IsHidden=T|Text=Yageo|Name=Manufacturer
|RECORD=41|OwnerIndex=2325|IndexInSheet=29|OwnerPartId=-1|Location.X=1331|Location.Y=502|Color=8388608|FontID=3|IsHidden=T|Text=http://www.yageo.com/|Name=Manufacturer URL
|RECORD=41|OwnerIndex=2325|IndexInSheet=30|OwnerPartId=-1|Location.X=1331|Location.Y=502|Color=8388608|FontID=1|IsHidden=T|Text=SurfaceMount|Name=Mount
|RECORD=41|OwnerIndex=2325|IndexInSheet=31|OwnerPartId=-1|Location.X=1331|Location.Y=502|Color=8388608|FontID=1|IsHidden=T|Text=1005|Name=Case Code (Metric)
|RECORD=41|OwnerIndex=2325|IndexInSheet=32|OwnerPartId=-1|Location.X=1331|Location.Y=502|Color=8388608|FontID=1|IsHidden=T|Text=100GR|Name=Insulation Resistance
|RECORD=41|OwnerIndex=2325|IndexInSheet=33|OwnerPartId=-1|Location.X=1331|Location.Y=502|Color=8388608|FontID=1|IsHidden=T|Text=0402|Name=Case/Package
|RECORD=41|OwnerIndex=2325|IndexInSheet=34|OwnerPartId=-1|Location.X=1331|Location.Y=502|Color=8388608|FontID=1|IsHidden=T|Text=5%|Name=Tolerance
|RECORD=41|OwnerIndex=2325|IndexInSheet=35|OwnerPartId=-1|Location.X=1331|Location.Y=502|Color=8388608|FontID=1|IsHidden=T|Text=SMD/SMT|Name=Termination
|RECORD=41|OwnerIndex=2325|IndexInSheet=36|OwnerPartId=-1|Location.X=1331|Location.Y=502|Color=8388608|FontID=1|IsHidden=T|Text=0.02inch|Name=Width
|RECORD=41|OwnerIndex=2325|IndexInSheet=37|OwnerPartId=-1|Location.X=1331|Location.Y=502|Color=8388608|FontID=1|IsHidden=T|Text=Rev. 14, 07/2016|Name=Datasheet Version
|RECORD=41|OwnerIndex=2325|IndexInSheet=38|OwnerPartId=-1|Location.X=1331|Location.Y=502|Color=8388608|FontID=1|IsHidden=T|Text=LeadFree|Name=Lead Free
|RECORD=41|OwnerIndex=2325|IndexInSheet=39|OwnerPartId=-1|Location.X=1331|Location.Y=502|Color=8388608|FontID=1|IsHidden=T|Text=0402|Name=Case Code (Imperial)
|RECORD=34|OwnerIndex=2325|IndexInSheet=-1|OwnerPartId=-1|Location.X=1349|Location.Y=481|Color=8388608|FontID=1|Text=C39|Name=Designator|ReadOnlyState=1
|RECORD=41|OwnerIndex=2325|IndexInSheet=-1|OwnerPartId=-1|Location.X=1349|Location.Y=471|Color=8388608|FontID=1|Text=22pF_50V_0402|Name=Comment
|RECORD=44|OwnerIndex=2325
|RECORD=45|OwnerIndex=2370|IndexInSheet=-1|Description=Chip Capacitor, 2-Leads, Body 1.00x0.50mm, IPC Low Density|UseComponentLibrary=T|ModelName=CAPC1005X55X25ML05T05|ModelType=PCBLIB|DatafileCount=1|ModelDatafileEntity0=CAPC1005X55X25ML05T05|ModelDatafileKind0=PCBLib|IsCurrent=T|DatalinksLocked=T|DatabaseDatalinksLocked=T
|RECORD=46|OwnerIndex=2371
|RECORD=48|OwnerIndex=2371
|RECORD=41|OwnerIndex=2373|IndexInSheet=-1|OwnerPartId=-1|Color=8388608|FontID=1|IsHidden=T|Text=2D|Name=Available Preview Images
|RECORD=45|OwnerIndex=2370|IndexInSheet=-1|Description=Chip Capacitor, 2-Leads, Body 1.00x0.50mm, IPC Medium Density|UseComponentLibrary=T|ModelName=CAPC1005X55X25NL05T05|ModelType=PCBLIB|DatafileCount=1|ModelDatafileEntity0=CAPC1005X55X25NL05T05|ModelDatafileKind0=PCBLib|DatalinksLocked=T|DatabaseDatalinksLocked=T
|RECORD=46|OwnerIndex=2375
|RECORD=48|OwnerIndex=2375
|RECORD=41|OwnerIndex=2377|IndexInSheet=-1|OwnerPartId=-1|Color=8388608|FontID=1|IsHidden=T|Text=2D|Name=Available Preview Images
|RECORD=45|OwnerIndex=2370|IndexInSheet=-1|Description=Chip Capacitor, 2-Leads, Body 1.00x0.50mm, IPC High Density|UseComponentLibrary=T|ModelName=CAPC1005X55X25LL05T05|ModelType=PCBLIB|DatafileCount=1|ModelDatafileEntity0=CAPC1005X55X25LL05T05|ModelDatafileKind0=PCBLib|DatalinksLocked=T|DatabaseDatalinksLocked=T
|RECORD=46|OwnerIndex=2379
|RECORD=48|OwnerIndex=2379
|RECORD=41|OwnerIndex=2381|IndexInSheet=-1|OwnerPartId=-1|Color=8388608|FontID=1|IsHidden=T|Text=2D|Name=Available Preview Images
|RECORD=17|IndexInSheet=205|OwnerPartId=-1|Style=4|ShowNetName=T|Location.X=1340|Location.Y=460|Orientation=3|Color=128|FontID=1|Text=GND
|RECORD=17|IndexInSheet=206|OwnerPartId=-1|Style=4|ShowNetName=T|Location.X=1420|Location.Y=460|Orientation=3|Color=128|FontID=1|Text=GND
|RECORD=1|LibReference=RES-2|ComponentDescription=Chip Resistor, 0 Ohm, 0.1 W, -55 to 155 degC, 0402 (1005 Metric), RoHS, Tape and Reel|PartCount=2|DisplayModeCount=1|IndexInSheet=207|OwnerPartId=-1|Location.X=1450|Location.Y=510|CurrentPartId=1|LibraryPath=*|SourceLibraryName=Altium Content Vault|TargetFileName=*|AreaColor=11599871|Color=128|PartIDLocked=T|DesignItemId=CMP-2000-07451-1|AllPinCount=2|ComponentKindVersion2=5
|RECORD=2|OwnerIndex=2385|OwnerPartId=1|FormalType=1|Electrical=4|PinConglomerate=32|PinLength=10|Location.X=1470|Location.Y=510|Name=2|Designator=2|PinPropagationDelay=0.000000E+000
|RECORD=2|OwnerIndex=2385|OwnerPartId=1|FormalType=1|Electrical=4|PinConglomerate=34|PinLength=10|Location.X=1450|Location.Y=510|Name=1|Designator=1|PinPropagationDelay=0.000000E+000
|RECORD=6|OwnerIndex=2385|IsNotAccesible=T|IndexInSheet=2|OwnerPartId=1|LineWidth=1|Color=16711680|LocationCount=10|X1=1470|Y1=510|X2=1466|Y2=510|X3=1465|Y3=508|X4=1463|Y4=512|X5=1461|Y5=508|X6=1459|Y6=512|X7=1457|Y7=508|X8=1455|Y8=512|X9=1454|Y9=510|X10=1450|Y10=510
|RECORD=41|OwnerIndex=2385|IndexInSheet=3|OwnerPartId=-1|Location.X=1438|Location.Y=525|Color=8388608|FontID=1|IsHidden=T|Text=50V|Name=Voltage Rating (DC)
|RECORD=41|OwnerIndex=2385|IndexInSheet=4|OwnerPartId=-1|Location.X=1438|Location.Y=525|Color=8388608|FontID=1|IsHidden=T|Text=2|Name=Number of Terminations
|RECORD=41|OwnerIndex=2385|IndexInSheet=5|OwnerPartId=-1|Location.X=1438|Location.Y=525|Color=8388608|FontID=1|IsHidden=T|Text=SurfaceMount|Name=Mount
|RECORD=41|OwnerIndex=2385|IndexInSheet=6|OwnerPartId=-1|Location.X=1438|Location.Y=525|Color=8388608|FontID=1|IsHidden=T|Text=0.35mm|Name=Height
|RECORD=41|OwnerIndex=2385|IndexInSheet=7|OwnerPartId=-1|Location.X=1438|Location.Y=525|Color=8388608|FontID=1|IsHidden=T|Text=TapeandReel|Name=Packaging
|RECORD=41|OwnerIndex=2385|IndexInSheet=8|OwnerPartId=-1|Location.X=1438|Location.Y=525|Color=8388608|FontID=1|IsHidden=T|Text=Tin|Name=Contact Plating
|RECORD=41|OwnerIndex=2385|IndexInSheet=9|OwnerPartId=-1|Location.X=1438|Location.Y=525|Color=8388608|FontID=3|IsHidden=T|Text=http://www.panasonic.com/|Name=Manufacturer URL
|RECORD=41|OwnerIndex=2385|IndexInSheet=10|OwnerPartId=-1|Location.X=1438|Location.Y=525|Color=8388608|FontID=1|IsHidden=T|Text=ThickFilm|Name=Composition
|RECORD=41|OwnerIndex=2385|IndexInSheet=11|OwnerPartId=-1|Location.X=1438|Location.Y=525|Color=8388608|FontID=1|IsHidden=T|Text=155degC|Name=Max Operating Temperature
|RECORD=41|OwnerIndex=2385|IndexInSheet=12|OwnerPartId=-1|Location.X=1438|Location.Y=525|Color=8388608|FontID=1|IsHidden=T|Text=600ppm/??C|Name=Temperature Coefficient
|RECORD=41|OwnerIndex=2385|IndexInSheet=13|OwnerPartId=-1|Location.X=1438|Location.Y=525|Color=8388608|FontID=1|IsHidden=T|Text=NoSVHC|Name=REACH SVHC
|RECORD=41|OwnerIndex=2385|IndexInSheet=14|OwnerPartId=-1|Location.X=1438|Location.Y=525|Color=8388608|FontID=1|IsHidden=T|Text=0402|Name=Case/Package
|RECORD=41|OwnerIndex=2385|IndexInSheet=15|OwnerPartId=-1|Location.X=1438|Location.Y=525|Color=8388608|FontID=1|IsHidden=T|Text=100mW|Name=Max Power Dissipation
|RECORD=41|OwnerIndex=2385|IndexInSheet=16|OwnerPartId=-1|Location.X=1438|Location.Y=525|Color=8388608|FontID=1|IsHidden=T|Text=402|Name=Package Reference
|RECORD=41|OwnerIndex=2385|IndexInSheet=17|OwnerPartId=-1|Location.X=1438|Location.Y=525|Color=8388608|FontID=1|IsHidden=T|Text=0.5mm|Name=Depth
|RECORD=41|OwnerIndex=2385|IndexInSheet=18|OwnerPartId=-1|Location.X=1438|Location.Y=525|Color=8388608|FontID=1|IsHidden=T|Text=Panasonic|Name=Manufacturer
|RECORD=41|OwnerIndex=2385|IndexInSheet=19|OwnerPartId=-1|Location.X=1438|Location.Y=525|Color=8388608|FontID=1|IsHidden=T|Text=2-Pin Surface Mount Device, Body 1 x 0.5 mm|Name=Package Description
|RECORD=41|OwnerIndex=2385|IndexInSheet=20|OwnerPartId=-1|Location.X=1438|Location.Y=525|Color=8388608|FontID=3|IsHidden=T|Text=https://industrial.panasonic.com/cdbs/www-data/pdf/RDA0000/AOA0000C301.pdf|Name=Datasheet URL
|RECORD=41|OwnerIndex=2385|IndexInSheet=21|OwnerPartId=-1|Location.X=1438|Location.Y=525|Color=8388608|FontID=1|IsHidden=T|Text=True|Name=RoHSCompliant
|RECORD=41|OwnerIndex=2385|IndexInSheet=22|OwnerPartId=-1|Location.X=1438|Location.Y=525|Color=8388608|FontID=1|IsHidden=T|Text=0402|Name=Case Code (Imperial)
|RECORD=41|OwnerIndex=2385|IndexInSheet=23|OwnerPartId=-1|Location.X=1438|Location.Y=525|Color=8388608|FontID=1|IsHidden=T|Text=0mOhm|Name=Resistance
|RECORD=41|OwnerIndex=2385|IndexInSheet=24|OwnerPartId=-1|Location.X=1438|Location.Y=525|Color=8388608|FontID=1|IsHidden=T|Text=Not|Name=Military Standard
|RECORD=41|OwnerIndex=2385|IndexInSheet=25|OwnerPartId=-1|Location.X=1438|Location.Y=525|Color=8388608|FontID=1|IsHidden=T|Text=5%|Name=Tolerance
|RECORD=41|OwnerIndex=2385|IndexInSheet=26|OwnerPartId=-1|Location.X=1438|Location.Y=525|Color=8388608|FontID=1|IsHidden=T|Text=-55degC|Name=Min Operating Temperature
|RECORD=41|OwnerIndex=2385|IndexInSheet=27|OwnerPartId=-1|Location.X=1438|Location.Y=525|Color=8388608|FontID=1|IsHidden=T|Text=100mW|Name=Power Rating
|RECORD=41|OwnerIndex=2385|IndexInSheet=28|OwnerPartId=-1|Location.X=1438|Location.Y=525|Color=8388608|FontID=1|IsHidden=T|Text=03/2015|Name=Datasheet Version
|RECORD=41|OwnerIndex=2385|IndexInSheet=29|OwnerPartId=-1|Location.X=1438|Location.Y=525|Color=8388608|FontID=1|IsHidden=T|Text=1mm|Name=Length
|RECORD=41|OwnerIndex=2385|IndexInSheet=30|OwnerPartId=-1|Location.X=1438|Location.Y=525|Color=8388608|FontID=1|IsHidden=T|Text=1005|Name=Case Code (Metric)
|RECORD=41|OwnerIndex=2385|IndexInSheet=31|OwnerPartId=-1|Location.X=1438|Location.Y=525|Color=8388608|FontID=1|IsHidden=T|Text=SMD/SMT|Name=Termination
|RECORD=41|OwnerIndex=2385|IndexInSheet=32|OwnerPartId=-1|Location.X=1438|Location.Y=525|Color=8388608|FontID=1|IsHidden=T|Text=SurfaceMount|Name=Mounting Technology
|RECORD=41|OwnerIndex=2385|IndexInSheet=33|OwnerPartId=-1|Location.X=1438|Location.Y=525|Color=8388608|FontID=1|IsHidden=T|Text=50V|Name=Voltage Rating
|RECORD=41|OwnerIndex=2385|IndexInSheet=34|OwnerPartId=-1|Location.X=1438|Location.Y=525|Color=8388608|FontID=1|IsHidden=T|Text=0.02inch|Name=Width
|RECORD=41|OwnerIndex=2385|IndexInSheet=35|OwnerPartId=-1|Location.X=1438|Location.Y=525|Color=8388608|FontID=1|IsHidden=T|Text=1|Name=Package Quantity
|RECORD=41|OwnerIndex=2385|IndexInSheet=36|OwnerPartId=-1|Location.X=1438|Location.Y=525|Color=8388608|FontID=1|IsHidden=T|Text=LeadFree|Name=Lead Free
|RECORD=41|OwnerIndex=2385|IndexInSheet=37|OwnerPartId=-1|Location.X=1438|Location.Y=525|Color=8388608|FontID=1|IsHidden=T|Text=No|Name=Radiation Hardening
|RECORD=34|OwnerIndex=2385|IndexInSheet=-1|OwnerPartId=-1|Location.X=1430|Location.Y=510|Color=8388608|FontID=1|Text=R73|Name=Designator|ReadOnlyState=1
|RECORD=41|OwnerIndex=2385|IndexInSheet=-1|OwnerPartId=-1|Location.X=1470|Location.Y=510|Color=8388608|FontID=1|Text=DNI_0_1%_0402|Name=Comment
|RECORD=44|OwnerIndex=2385
|RECORD=45|OwnerIndex=2428|IndexInSheet=-1|Description=Chip Resistor, 2-Leads, Body 1.05x0.55mm, IPC High Density|UseComponentLibrary=T|ModelName=RESC1005X40X25LL05T05|ModelType=PCBLIB|DatafileCount=1|ModelDatafileEntity0=RESC1005X40X25LL05T05|ModelDatafileKind0=PCBLib|IsCurrent=T|DatalinksLocked=T|DatabaseDatalinksLocked=T
|RECORD=46|OwnerIndex=2429
|RECORD=48|OwnerIndex=2429
|RECORD=41|OwnerIndex=2431|IndexInSheet=-1|OwnerPartId=-1|Color=8388608|FontID=1|IsHidden=T|Text=2D|Name=Available Preview Images
|RECORD=45|OwnerIndex=2428|IndexInSheet=-1|Description=Chip Resistor, 2-Leads, Body 1.05x0.55mm, IPC Low Density|UseComponentLibrary=T|ModelName=RESC1005X40X25ML05T05|ModelType=PCBLIB|DatafileCount=1|ModelDatafileEntity0=RESC1005X40X25ML05T05|ModelDatafileKind0=PCBLib|DatalinksLocked=T|DatabaseDatalinksLocked=T
|RECORD=46|OwnerIndex=2433
|RECORD=48|OwnerIndex=2433
|RECORD=41|OwnerIndex=2435|IndexInSheet=-1|OwnerPartId=-1|Color=8388608|FontID=1|IsHidden=T|Text=2D|Name=Available Preview Images
|RECORD=45|OwnerIndex=2428|IndexInSheet=-1|Description=Chip Resistor, 2-Leads, Body 1.05x0.55mm, IPC Medium Density|UseComponentLibrary=T|ModelName=RESC1005X40X25NL05T05|ModelType=PCBLIB|DatafileCount=1|ModelDatafileEntity0=RESC1005X40X25NL05T05|ModelDatafileKind0=PCBLib|DatalinksLocked=T|DatabaseDatalinksLocked=T
|RECORD=46|OwnerIndex=2437
|RECORD=48|OwnerIndex=2437
|RECORD=41|OwnerIndex=2439|IndexInSheet=-1|OwnerPartId=-1|Color=8388608|FontID=1|IsHidden=T|Text=2D|Name=Available Preview Images
|RECORD=17|IndexInSheet=208|OwnerPartId=-1|ShowNetName=T|Location.X=1530|Location.Y=510|Color=255|FontID=1|Text=FPGA_BNO_XOUT32|IsCrossSheetConnector=T
|RECORD=1|LibReference=a38d0f79c2a9f01c07a7e52882ed186|ComponentDescription=IC REG LINEAR 3.3V 500MA 6XDFN|PartCount=2|DisplayModeCount=1|IndexInSheet=209|OwnerPartId=-1|Location.X=1080|Location.Y=710|CurrentPartId=1|LibraryPath=*|SourceLibraryName=Altium Content Vault|TargetFileName=*|AreaColor=11599871|Color=128|PartIDLocked=T|DesignItemId=CMP-07128-000022-1|AllPinCount=7
|RECORD=14|OwnerIndex=2442|IsNotAccesible=T|OwnerPartId=1|Location.X=1100|Location.Y=630|Corner.X=1170|Corner.Y=720|LineWidth=1|Color=128|AreaColor=11599871|IsSolid=T
|RECORD=2|OwnerIndex=2442|OwnerPartId=1|PinConglomerate=58|PinLength=20|Location.X=1100|Location.Y=690|Name=EN|Designator=4|PinPropagationDelay=0.000000E+000
|RECORD=2|OwnerIndex=2442|OwnerPartId=1|PinConglomerate=56|PinLength=20|Location.X=1170|Location.Y=690|Name=FB|Designator=2|PinPropagationDelay=0.000000E+000
|RECORD=2|OwnerIndex=2442|OwnerPartId=1|Electrical=7|PinConglomerate=58|PinLength=20|Location.X=1100|Location.Y=710|Name=IN|Designator=6|PinPropagationDelay=0.000000E+000
|RECORD=2|OwnerIndex=2442|OwnerPartId=1|Electrical=4|PinConglomerate=56|PinLength=20|Location.X=1170|Location.Y=670|Name=NC|Designator=5|PinPropagationDelay=0.000000E+000
|RECORD=2|OwnerIndex=2442|OwnerPartId=1|Electrical=2|PinConglomerate=56|PinLength=20|Location.X=1170|Location.Y=710|Name=OUT|Designator=1|PinPropagationDelay=0.000000E+000
|RECORD=2|OwnerIndex=2442|OwnerPartId=1|Electrical=7|PinConglomerate=56|PinLength=20|Location.X=1170|Location.Y=650|Name=GND|Designator=3|PinPropagationDelay=0.000000E+000
|RECORD=2|OwnerIndex=2442|OwnerPartId=1|Electrical=7|PinConglomerate=56|PinLength=20|Location.X=1170|Location.Y=640|Name=GND|Designator=7|PinPropagationDelay=0.000000E+000
|RECORD=41|OwnerIndex=2442|IndexInSheet=8|OwnerPartId=-1|Location.X=1078|Location.Y=720|Color=8388608|FontID=3|IsHidden=T|Text=https://www.onsemi.com/pub/Collateral/711AT.PDF|Name=Footprint Url
|RECORD=41|OwnerIndex=2442|IndexInSheet=9|OwnerPartId=-1|Location.X=1078|Location.Y=720|Color=8388608|FontID=1|IsHidden=T|Text=Power Management ICs|Name=Device Class L2
|RECORD=41|OwnerIndex=2442|IndexInSheet=10|OwnerPartId=-1|Location.X=1078|Location.Y=720|Color=8388608|FontID=1|IsHidden=T|Text=Integrated Circuits (ICs)|Name=Device Class L1
|RECORD=41|OwnerIndex=2442|IndexInSheet=11|OwnerPartId=-1|Location.X=1078|Location.Y=720|Color=8388608|FontID=1|IsHidden=T|Text=IC REG LINEAR 3.3V 500MA 6XDFN|Name=Digikey Description
|RECORD=41|OwnerIndex=2442|IndexInSheet=12|OwnerPartId=-1|Location.X=1078|Location.Y=720|Color=8388608|FontID=1|IsHidden=T|Text=Datasheet|Name=ComponentLink2Description
|RECORD=41|OwnerIndex=2442|IndexInSheet=13|OwnerPartId=-1|Location.X=1078|Location.Y=720|Color=8388608|FontID=1|IsHidden=T|Text=3.3V|Name=Output Voltage
|RECORD=41|OwnerIndex=2442|IndexInSheet=14|OwnerPartId=-1|Location.X=1078|Location.Y=720|Color=8388608|FontID=1|IsHidden=T|Text=Fixed|Name=Output Type
|RECORD=41|OwnerIndex=2442|IndexInSheet=15|OwnerPartId=-1|Location.X=1078|Location.Y=720|Color=8388608|FontID=3|IsHidden=T|Text=https://www.onsemi.com/pub/Collateral/NCP176-D.PDF|Name=ComponentLink2URL
|RECORD=41|OwnerIndex=2442|IndexInSheet=16|OwnerPartId=-1|Location.X=1078|Location.Y=720|Color=8388608|FontID=1|IsHidden=T|Text=TRUE|Name=RoHS
|RECORD=41|OwnerIndex=2442|IndexInSheet=17|OwnerPartId=-1|Location.X=1078|Location.Y=720|Color=8388608|FontID=1|IsHidden=T|Text=295mV|Name=Dropout Voltage
|RECORD=41|OwnerIndex=2442|IndexInSheet=18|OwnerPartId=-1|Location.X=1078|Location.Y=720|Color=8388608|FontID=1|IsHidden=T|Text=1|Name=Number Of Outputs
|RECORD=41|OwnerIndex=2442|IndexInSheet=19|OwnerPartId=-1|Location.X=1078|Location.Y=720|Color=8388608|FontID=1|IsHidden=T|Text=ON Semiconductor|Name=Manufacturer
|RECORD=41|OwnerIndex=2442|IndexInSheet=20|OwnerPartId=-1|Location.X=1078|Location.Y=720|Color=8388608|FontID=1|IsHidden=T|Text=Yes|Name=Lead Free
|RECORD=41|OwnerIndex=2442|IndexInSheet=21|OwnerPartId=-1|Location.X=1078|Location.Y=720|Color=8388608|FontID=1|IsHidden=T|Text=500mA|Name=Output Current
|RECORD=41|OwnerIndex=2442|IndexInSheet=22|OwnerPartId=-1|Location.X=1078|Location.Y=720|Color=8388608|FontID=1|IsHidden=T|Text=No|Name=Automotive
|RECORD=41|OwnerIndex=2442|IndexInSheet=23|OwnerPartId=-1|Location.X=1078|Location.Y=720|Color=8388608|FontID=1|IsHidden=T|Text=+150°C|Name=Temperature Range High
|RECORD=41|OwnerIndex=2442|IndexInSheet=24|OwnerPartId=-1|Location.X=1078|Location.Y=720|Color=8388608|FontID=1|IsHidden=T|Text=0.45mm|Name=Height
|RECORD=41|OwnerIndex=2442|IndexInSheet=25|OwnerPartId=-1|Location.X=1078|Location.Y=720|Color=8388608|FontID=1|IsHidden=T|Text=0mm|Name=Standoff Height
|RECORD=41|OwnerIndex=2442|IndexInSheet=26|OwnerPartId=-1|Location.X=1078|Location.Y=720|Color=8388608|FontID=1|IsHidden=T|Text=1.4V|Name=Min Supply Voltage
|RECORD=41|OwnerIndex=2442|IndexInSheet=27|OwnerPartId=-1|Location.X=1078|Location.Y=720|Color=8388608|FontID=1|IsHidden=T|Text=60uA|Name=Nominal Supply Current
|RECORD=41|OwnerIndex=2442|IndexInSheet=28|OwnerPartId=-1|Location.X=1078|Location.Y=720|Color=8388608|FontID=1|IsHidden=T|Text=5.5V|Name=Max Supply Voltage
|RECORD=41|OwnerIndex=2442|IndexInSheet=29|OwnerPartId=-1|Location.X=1078|Location.Y=720|Color=8388608|FontID=1|IsHidden=T|Text=711AT|Name=Package
|RECORD=41|OwnerIndex=2442|IndexInSheet=30|OwnerPartId=-1|Location.X=1078|Location.Y=720|Color=8388608|FontID=1|IsHidden=T|Text=Voltage Regulators - Linear|Name=Device Class L3
|RECORD=41|OwnerIndex=2442|IndexInSheet=31|OwnerPartId=-1|Location.X=1078|Location.Y=720|Color=8388608|FontID=1|IsHidden=T|Text=+150°C|Name=Max Junction Temp
|RECORD=41|OwnerIndex=2442|IndexInSheet=32|OwnerPartId=-1|Location.X=1078|Location.Y=720|Color=8388608|FontID=3|IsHidden=T|Text=https://octopart.com/ncp176amx330tcg-on+semiconductor-61522616|Name=Octopart
|RECORD=41|OwnerIndex=2442|IndexInSheet=33|OwnerPartId=-1|Location.X=1078|Location.Y=720|Color=8388608|FontID=1|IsHidden=T|Text=IC|Name=Category
|RECORD=41|OwnerIndex=2442|IndexInSheet=34|OwnerPartId=-1|Location.X=1078|Location.Y=720|Color=8388608|FontID=1|IsHidden=T|Text=0.8%|Name=Accuracy Percentage
|RECORD=41|OwnerIndex=2442|IndexInSheet=35|OwnerPartId=-1|Location.X=1078|Location.Y=720|Color=8388608|FontID=1|IsHidden=T|Text=NCP176AMX330TCG|Name=Manufacturer Part Number
|RECORD=41|OwnerIndex=2442|IndexInSheet=36|OwnerPartId=-1|Location.X=1078|Location.Y=720|Color=8388608|FontID=1|IsHidden=T|Text=DFN120X120X37-6|Name=Ipc Land Pattern Name
|RECORD=41|OwnerIndex=2442|IndexInSheet=37|OwnerPartId=-1|Location.X=1078|Location.Y=720|Color=8388608|FontID=1|IsHidden=T|Text=to +150°C|Name=Temperature
|RECORD=34|OwnerIndex=2442|IndexInSheet=-1|OwnerPartId=-1|Location.X=1100|Location.Y=720|Color=8388608|FontID=1|Text=U25|Name=Designator|ReadOnlyState=1
|RECORD=41|OwnerIndex=2442|IndexInSheet=-1|OwnerPartId=1|Location.X=1100|Location.Y=620|Color=8388608|FontID=1|Text=NCP176AMX330TCG|Name=Comment
|RECORD=44|OwnerIndex=2442
|RECORD=45|OwnerIndex=2490|IndexInSheet=-1|UseComponentLibrary=T|ModelName=FP-711AT-MFG|ModelType=PCBLIB|DatafileCount=1|ModelDatafileEntity0=FP-711AT-MFG|ModelDatafileKind0=PCBLib|IsCurrent=T|DatalinksLocked=T|DatabaseDatalinksLocked=T
|RECORD=46|OwnerIndex=2491
|RECORD=48|OwnerIndex=2491
|RECORD=45|OwnerIndex=2490|IndexInSheet=-1|UseComponentLibrary=T|ModelName=FP-711AT-IPC_C|ModelType=PCBLIB|DatafileCount=1|ModelDatafileEntity0=FP-711AT-IPC_C|ModelDatafileKind0=PCBLib|DatalinksLocked=T|DatabaseDatalinksLocked=T
|RECORD=46|OwnerIndex=2494
|RECORD=48|OwnerIndex=2494
|RECORD=45|OwnerIndex=2490|IndexInSheet=-1|UseComponentLibrary=T|ModelName=FP-711AT-IPC_B|ModelType=PCBLIB|DatafileCount=1|ModelDatafileEntity0=FP-711AT-IPC_B|ModelDatafileKind0=PCBLib|DatalinksLocked=T|DatabaseDatalinksLocked=T
|RECORD=46|OwnerIndex=2497
|RECORD=48|OwnerIndex=2497
|RECORD=45|OwnerIndex=2490|IndexInSheet=-1|UseComponentLibrary=T|ModelName=FP-711AT-IPC_A|ModelType=PCBLIB|DatafileCount=1|ModelDatafileEntity0=FP-711AT-IPC_A|ModelDatafileKind0=PCBLib|DatalinksLocked=T|DatabaseDatalinksLocked=T
|RECORD=46|OwnerIndex=2500
|RECORD=48|OwnerIndex=2500
|RECORD=1|LibReference=RES-2|ComponentDescription=Chip Resistor, 0 Ohm, 0.1 W, -55 to 155 degC, 0402 (1005 Metric), RoHS, Tape and Reel|PartCount=2|DisplayModeCount=1|IndexInSheet=210|OwnerPartId=-1|Location.X=1320|Location.Y=510|Orientation=2|CurrentPartId=1|LibraryPath=*|SourceLibraryName=Altium Content Vault|TargetFileName=*|AreaColor=11599871|Color=128|PartIDLocked=T|DesignItemId=CMP-2000-07451-1|AllPinCount=2|ComponentKindVersion2=5
|RECORD=2|OwnerIndex=2503|OwnerPartId=1|FormalType=1|Electrical=4|PinConglomerate=34|PinLength=10|Location.X=1300|Location.Y=510|Name=2|Designator=2|PinPropagationDelay=0.000000E+000
|RECORD=2|OwnerIndex=2503|OwnerPartId=1|FormalType=1|Electrical=4|PinConglomerate=32|PinLength=10|Location.X=1320|Location.Y=510|Name=1|Designator=1|PinPropagationDelay=0.000000E+000
|RECORD=6|OwnerIndex=2503|IsNotAccesible=T|IndexInSheet=2|OwnerPartId=1|LineWidth=1|Color=16711680|LocationCount=10|X1=1300|Y1=510|X2=1304|Y2=510|X3=1305|Y3=512|X4=1307|Y4=508|X5=1309|Y5=512|X6=1311|Y6=508|X7=1313|Y7=512|X8=1315|Y8=508|X9=1316|Y9=510|X10=1320|Y10=510
|RECORD=41|OwnerIndex=2503|IndexInSheet=3|OwnerPartId=-1|Location.X=1288|Location.Y=513|Color=8388608|FontID=1|IsHidden=T|Text=50V|Name=Voltage Rating (DC)
|RECORD=41|OwnerIndex=2503|IndexInSheet=4|OwnerPartId=-1|Location.X=1288|Location.Y=513|Color=8388608|FontID=1|IsHidden=T|Text=2|Name=Number of Terminations
|RECORD=41|OwnerIndex=2503|IndexInSheet=5|OwnerPartId=-1|Location.X=1288|Location.Y=513|Color=8388608|FontID=1|IsHidden=T|Text=SurfaceMount|Name=Mount
|RECORD=41|OwnerIndex=2503|IndexInSheet=6|OwnerPartId=-1|Location.X=1288|Location.Y=513|Color=8388608|FontID=1|IsHidden=T|Text=0.35mm|Name=Height
|RECORD=41|OwnerIndex=2503|IndexInSheet=7|OwnerPartId=-1|Location.X=1288|Location.Y=513|Color=8388608|FontID=1|IsHidden=T|Text=TapeandReel|Name=Packaging
|RECORD=41|OwnerIndex=2503|IndexInSheet=8|OwnerPartId=-1|Location.X=1288|Location.Y=513|Color=8388608|FontID=1|IsHidden=T|Text=Tin|Name=Contact Plating
|RECORD=41|OwnerIndex=2503|IndexInSheet=9|OwnerPartId=-1|Location.X=1288|Location.Y=513|Color=8388608|FontID=3|IsHidden=T|Text=http://www.panasonic.com/|Name=Manufacturer URL
|RECORD=41|OwnerIndex=2503|IndexInSheet=10|OwnerPartId=-1|Location.X=1288|Location.Y=513|Color=8388608|FontID=1|IsHidden=T|Text=ThickFilm|Name=Composition
|RECORD=41|OwnerIndex=2503|IndexInSheet=11|OwnerPartId=-1|Location.X=1288|Location.Y=513|Color=8388608|FontID=1|IsHidden=T|Text=155degC|Name=Max Operating Temperature
|RECORD=41|OwnerIndex=2503|IndexInSheet=12|OwnerPartId=-1|Location.X=1288|Location.Y=513|Color=8388608|FontID=1|IsHidden=T|Text=600ppm/??C|Name=Temperature Coefficient
|RECORD=41|OwnerIndex=2503|IndexInSheet=13|OwnerPartId=-1|Location.X=1288|Location.Y=513|Color=8388608|FontID=1|IsHidden=T|Text=NoSVHC|Name=REACH SVHC
|RECORD=41|OwnerIndex=2503|IndexInSheet=14|OwnerPartId=-1|Location.X=1288|Location.Y=513|Color=8388608|FontID=1|IsHidden=T|Text=0402|Name=Case/Package
|RECORD=41|OwnerIndex=2503|IndexInSheet=15|OwnerPartId=-1|Location.X=1288|Location.Y=513|Color=8388608|FontID=1|IsHidden=T|Text=100mW|Name=Max Power Dissipation
|RECORD=41|OwnerIndex=2503|IndexInSheet=16|OwnerPartId=-1|Location.X=1288|Location.Y=513|Color=8388608|FontID=1|IsHidden=T|Text=402|Name=Package Reference
|RECORD=41|OwnerIndex=2503|IndexInSheet=17|OwnerPartId=-1|Location.X=1288|Location.Y=513|Color=8388608|FontID=1|IsHidden=T|Text=0.5mm|Name=Depth
|RECORD=41|OwnerIndex=2503|IndexInSheet=18|OwnerPartId=-1|Location.X=1288|Location.Y=513|Color=8388608|FontID=1|IsHidden=T|Text=Panasonic|Name=Manufacturer
|RECORD=41|OwnerIndex=2503|IndexInSheet=19|OwnerPartId=-1|Location.X=1288|Location.Y=513|Color=8388608|FontID=1|IsHidden=T|Text=2-Pin Surface Mount Device, Body 1 x 0.5 mm|Name=Package Description
|RECORD=41|OwnerIndex=2503|IndexInSheet=20|OwnerPartId=-1|Location.X=1288|Location.Y=513|Color=8388608|FontID=3|IsHidden=T|Text=https://industrial.panasonic.com/cdbs/www-data/pdf/RDA0000/AOA0000C301.pdf|Name=Datasheet URL
|RECORD=41|OwnerIndex=2503|IndexInSheet=21|OwnerPartId=-1|Location.X=1288|Location.Y=513|Color=8388608|FontID=1|IsHidden=T|Text=True|Name=RoHSCompliant
|RECORD=41|OwnerIndex=2503|IndexInSheet=22|OwnerPartId=-1|Location.X=1288|Location.Y=513|Color=8388608|FontID=1|IsHidden=T|Text=0402|Name=Case Code (Imperial)
|RECORD=41|OwnerIndex=2503|IndexInSheet=23|OwnerPartId=-1|Location.X=1288|Location.Y=513|Color=8388608|FontID=1|IsHidden=T|Text=0mOhm|Name=Resistance
|RECORD=41|OwnerIndex=2503|IndexInSheet=24|OwnerPartId=-1|Location.X=1288|Location.Y=513|Color=8388608|FontID=1|IsHidden=T|Text=Not|Name=Military Standard
|RECORD=41|OwnerIndex=2503|IndexInSheet=25|OwnerPartId=-1|Location.X=1288|Location.Y=513|Color=8388608|FontID=1|IsHidden=T|Text=5%|Name=Tolerance
|RECORD=41|OwnerIndex=2503|IndexInSheet=26|OwnerPartId=-1|Location.X=1288|Location.Y=513|Color=8388608|FontID=1|IsHidden=T|Text=-55degC|Name=Min Operating Temperature
|RECORD=41|OwnerIndex=2503|IndexInSheet=27|OwnerPartId=-1|Location.X=1288|Location.Y=513|Color=8388608|FontID=1|IsHidden=T|Text=100mW|Name=Power Rating
|RECORD=41|OwnerIndex=2503|IndexInSheet=28|OwnerPartId=-1|Location.X=1288|Location.Y=513|Color=8388608|FontID=1|IsHidden=T|Text=03/2015|Name=Datasheet Version
|RECORD=41|OwnerIndex=2503|IndexInSheet=29|OwnerPartId=-1|Location.X=1288|Location.Y=513|Color=8388608|FontID=1|IsHidden=T|Text=1mm|Name=Length
|RECORD=41|OwnerIndex=2503|IndexInSheet=30|OwnerPartId=-1|Location.X=1288|Location.Y=513|Color=8388608|FontID=1|IsHidden=T|Text=1005|Name=Case Code (Metric)
|RECORD=41|OwnerIndex=2503|IndexInSheet=31|OwnerPartId=-1|Location.X=1288|Location.Y=513|Color=8388608|FontID=1|IsHidden=T|Text=SMD/SMT|Name=Termination
|RECORD=41|OwnerIndex=2503|IndexInSheet=32|OwnerPartId=-1|Location.X=1288|Location.Y=513|Color=8388608|FontID=1|IsHidden=T|Text=SurfaceMount|Name=Mounting Technology
|RECORD=41|OwnerIndex=2503|IndexInSheet=33|OwnerPartId=-1|Location.X=1288|Location.Y=513|Color=8388608|FontID=1|IsHidden=T|Text=50V|Name=Voltage Rating
|RECORD=41|OwnerIndex=2503|IndexInSheet=34|OwnerPartId=-1|Location.X=1288|Location.Y=513|Color=8388608|FontID=1|IsHidden=T|Text=0.02inch|Name=Width
|RECORD=41|OwnerIndex=2503|IndexInSheet=35|OwnerPartId=-1|Location.X=1288|Location.Y=513|Color=8388608|FontID=1|IsHidden=T|Text=1|Name=Package Quantity
|RECORD=41|OwnerIndex=2503|IndexInSheet=36|OwnerPartId=-1|Location.X=1288|Location.Y=513|Color=8388608|FontID=1|IsHidden=T|Text=LeadFree|Name=Lead Free
|RECORD=41|OwnerIndex=2503|IndexInSheet=37|OwnerPartId=-1|Location.X=1288|Location.Y=513|Color=8388608|FontID=1|IsHidden=T|Text=No|Name=Radiation Hardening
|RECORD=34|OwnerIndex=2503|IndexInSheet=-1|OwnerPartId=-1|Location.X=1299|Location.Y=513|Color=8388608|FontID=1|Text=R71|Name=Designator|ReadOnlyState=1
|RECORD=41|OwnerIndex=2503|IndexInSheet=-1|OwnerPartId=-1|Location.X=1299|Location.Y=497|Color=8388608|FontID=1|Text=DNI_0_1%_0402|Name=Comment
|RECORD=44|OwnerIndex=2503
|RECORD=45|OwnerIndex=2546|IndexInSheet=-1|Description=Chip Resistor, 2-Leads, Body 1.05x0.55mm, IPC High Density|UseComponentLibrary=T|ModelName=RESC1005X40X25LL05T05|ModelType=PCBLIB|DatafileCount=1|ModelDatafileEntity0=RESC1005X40X25LL05T05|ModelDatafileKind0=PCBLib|IsCurrent=T|DatalinksLocked=T|DatabaseDatalinksLocked=T
|RECORD=46|OwnerIndex=2547
|RECORD=48|OwnerIndex=2547
|RECORD=41|OwnerIndex=2549|IndexInSheet=-1|OwnerPartId=-1|Color=8388608|FontID=1|IsHidden=T|Text=2D|Name=Available Preview Images
|RECORD=45|OwnerIndex=2546|IndexInSheet=-1|Description=Chip Resistor, 2-Leads, Body 1.05x0.55mm, IPC Low Density|UseComponentLibrary=T|ModelName=RESC1005X40X25ML05T05|ModelType=PCBLIB|DatafileCount=1|ModelDatafileEntity0=RESC1005X40X25ML05T05|ModelDatafileKind0=PCBLib|DatalinksLocked=T|DatabaseDatalinksLocked=T
|RECORD=46|OwnerIndex=2551
|RECORD=48|OwnerIndex=2551
|RECORD=41|OwnerIndex=2553|IndexInSheet=-1|OwnerPartId=-1|Color=8388608|FontID=1|IsHidden=T|Text=2D|Name=Available Preview Images
|RECORD=45|OwnerIndex=2546|IndexInSheet=-1|Description=Chip Resistor, 2-Leads, Body 1.05x0.55mm, IPC Medium Density|UseComponentLibrary=T|ModelName=RESC1005X40X25NL05T05|ModelType=PCBLIB|DatafileCount=1|ModelDatafileEntity0=RESC1005X40X25NL05T05|ModelDatafileKind0=PCBLib|DatalinksLocked=T|DatabaseDatalinksLocked=T
|RECORD=46|OwnerIndex=2555
|RECORD=48|OwnerIndex=2555
|RECORD=41|OwnerIndex=2557|IndexInSheet=-1|OwnerPartId=-1|Color=8388608|FontID=1|IsHidden=T|Text=2D|Name=Available Preview Images
|RECORD=17|IndexInSheet=211|OwnerPartId=-1|ShowNetName=T|Location.X=1270|Location.Y=510|Orientation=2|Color=255|FontID=1|Text=FPGA_BNO_XIN32|IsCrossSheetConnector=T
|RECORD=17|IndexInSheet=212|OwnerPartId=-1|ShowNetName=T|Location.X=1240|Location.Y=730|Orientation=1|Color=128|FontID=1|Text=BNO_P3V3
|RECORD=17|IndexInSheet=213|OwnerPartId=-1|Style=4|ShowNetName=T|Location.X=1210|Location.Y=620|Orientation=3|Color=128|FontID=1|Text=GND
|RECORD=1|LibReference=b4654b650e69147ec39a6b967a45e02|ComponentDescription=Multilayer Ceramic Capacitor 10uF 16V X5R 20% SMD 0603 T/R|PartCount=2|DisplayModeCount=1|IndexInSheet=214|OwnerPartId=-1|Location.X=1235|Location.Y=670|CurrentPartId=1|LibraryPath=*|SourceLibraryName=Altium Content Vault|TargetFileName=*|AreaColor=11599871|Color=128|PartIDLocked=T|DesignItemId=CMP-2000-06226-4|AllPinCount=2
|RECORD=2|OwnerIndex=2562|OwnerPartId=1|Electrical=4|PinConglomerate=49|PinLength=7|Location.X=1235|Location.Y=663|Name=1|Designator=1|PinPropagationDelay=0.000000E+000
|RECORD=2|OwnerIndex=2562|OwnerPartId=1|Electrical=4|PinConglomerate=51|PinLength=6|Location.X=1235|Location.Y=656|Name=2|Designator=2|PinPropagationDelay=0.000000E+000
|RECORD=13|OwnerIndex=2562|IsNotAccesible=T|IndexInSheet=2|OwnerPartId=1|Location.X=1245|Location.Y=663|Corner.X=1225|Corner.Y=663|LineWidth=1|Color=16711680
|RECORD=13|OwnerIndex=2562|IsNotAccesible=T|IndexInSheet=3|OwnerPartId=1|Location.X=1245|Location.Y=657|Corner.X=1225|Corner.Y=657|LineWidth=1|Color=16711680
|RECORD=13|OwnerIndex=2562|IsNotAccesible=T|IndexInSheet=4|OwnerPartId=1|Location.X=1235|Location.Y=663|Corner.X=1235|Corner.Y=666|LineWidth=1|Color=16711680
|RECORD=13|OwnerIndex=2562|IsNotAccesible=T|IndexInSheet=5|OwnerPartId=1|Location.X=1235|Location.Y=656|Corner.X=1235|Corner.Y=655|LineWidth=1|Color=16711680
|RECORD=41|OwnerIndex=2562|IndexInSheet=6|OwnerPartId=-1|Location.X=1224|Location.Y=672|Color=8388608|FontID=1|IsHidden=T|Text=Tape and Reel|Name=Packaging
|RECORD=41|OwnerIndex=2562|IndexInSheet=7|OwnerPartId=-1|Location.X=1224|Location.Y=672|Color=8388608|FontID=1|IsHidden=T|Text=Flat|Name=Construction
|RECORD=41|OwnerIndex=2562|IndexInSheet=8|OwnerPartId=-1|Location.X=1224|Location.Y=672|Color=8388608|FontID=1|IsHidden=T|Text=0.8mm|Name=Height
|RECORD=41|OwnerIndex=2562|IndexInSheet=9|OwnerPartId=-1|Location.X=1224|Location.Y=672|Color=8388608|FontID=1|IsHidden=T|Text=85°C|Name=Max Operating Temperature
|RECORD=41|OwnerIndex=2562|IndexInSheet=10|OwnerPartId=-1|Location.X=1224|Location.Y=672|Color=8388608|FontID=1|IsHidden=T|Text=X5R|Name=Dielectric
|RECORD=41|OwnerIndex=2562|IndexInSheet=11|OwnerPartId=-1|Location.X=1224|Location.Y=672|Color=8388608|FontID=1|IsHidden=T|Text=1608|Name=Case Code (Metric)
|RECORD=41|OwnerIndex=2562|IndexInSheet=12|OwnerPartId=-1|Location.X=1224|Location.Y=672|Color=8388608|FontID=1|IsHidden=T|Text=16V|Name=Voltage Rating (DC)
|RECORD=41|OwnerIndex=2562|IndexInSheet=13|OwnerPartId=-1|Location.X=1224|Location.Y=672|Color=8388608|FontID=1|IsHidden=T|Text=0.031inch|Name=Width
|RECORD=41|OwnerIndex=2562|IndexInSheet=14|OwnerPartId=-1|Location.X=1224|Location.Y=672|Color=8388608|FontID=1|IsHidden=T|Text=16V|Name=Voltage Rating
|RECORD=41|OwnerIndex=2562|IndexInSheet=15|OwnerPartId=-1|Location.X=1224|Location.Y=672|Color=8388608|FontID=1|IsHidden=T|Text=0.063inch|Name=Length
|RECORD=41|OwnerIndex=2562|IndexInSheet=16|OwnerPartId=-1|Location.X=1224|Location.Y=672|Color=8388608|FontID=1|IsHidden=T|Text=Yes|Name=RoHS Compliant
|RECORD=41|OwnerIndex=2562|IndexInSheet=17|OwnerPartId=-1|Location.X=1224|Location.Y=672|Color=8388608|FontID=1|IsHidden=T|Text=Halogen Free|Name=Halogen Free
|RECORD=41|OwnerIndex=2562|IndexInSheet=18|OwnerPartId=-1|Location.X=1224|Location.Y=672|Color=8388608|FontID=1|IsHidden=T|Text=0603|Name=Case Code (Imperial)
|RECORD=41|OwnerIndex=2562|IndexInSheet=19|OwnerPartId=-1|Location.X=1224|Location.Y=672|Color=8388608|FontID=1|IsHidden=T|Text=10uF|Name=Capacitance
|RECORD=41|OwnerIndex=2562|IndexInSheet=20|OwnerPartId=-1|Location.X=1224|Location.Y=672|Color=8388608|FontID=1|IsHidden=T|Text=Surface Mount|Name=Mount
|RECORD=41|OwnerIndex=2562|IndexInSheet=21|OwnerPartId=-1|Location.X=1224|Location.Y=672|Color=8388608|FontID=1|IsHidden=T|Text=0.031inch|Name=Thickness
|RECORD=41|OwnerIndex=2562|IndexInSheet=22|OwnerPartId=-1|Location.X=1224|Location.Y=672|Color=8388608|FontID=1|IsHidden=T|Text=20%|Name=Tolerance
|RECORD=41|OwnerIndex=2562|IndexInSheet=23|OwnerPartId=-1|Location.X=1224|Location.Y=672|Color=8388608|FontID=1|IsHidden=T|Text=-55°C|Name=Min Operating Temperature
|RECORD=41|OwnerIndex=2562|IndexInSheet=24|OwnerPartId=-1|Location.X=1224|Location.Y=672|Color=8388608|FontID=1|IsHidden=T|Text=M|Name=Series
|RECORD=41|OwnerIndex=2562|IndexInSheet=25|OwnerPartId=-1|Location.X=1224|Location.Y=672|Color=8388608|FontID=1|IsHidden=T|Text=SMD/SMT|Name=Termination
|RECORD=41|OwnerIndex=2562|IndexInSheet=26|OwnerPartId=-1|Location.X=1224|Location.Y=672|Color=8388608|FontID=1|IsHidden=T|Text=0603|Name=Case/Package
|RECORD=41|OwnerIndex=2562|IndexInSheet=27|OwnerPartId=-1|Location.X=1224|Location.Y=672|Color=8388608|FontID=1|IsHidden=T|Text=1|Name=Package Quantity
|RECORD=34|OwnerIndex=2562|IndexInSheet=-1|OwnerPartId=-1|Location.X=1225|Location.Y=650|Orientation=1|Color=8388608|FontID=2|Text=C8|Name=Designator|ReadOnlyState=1
|RECORD=41|OwnerIndex=2562|IndexInSheet=-1|OwnerPartId=1|Location.X=1255|Location.Y=635|Orientation=1|Color=8388608|FontID=2|Text=10uF_16V_0603|Name=Comment
|RECORD=44|OwnerIndex=2562
|RECORD=45|OwnerIndex=2595|IndexInSheet=-1|UseComponentLibrary=T|ModelName=FP-0603-L_1_6_0_2-W_0_8_0-MFG|ModelType=PCBLIB|DatafileCount=1|ModelDatafileEntity0=FP-0603-L_1_6_0_2-W_0_8_0-MFG|ModelDatafileKind0=PCBLib|IsCurrent=T|DatalinksLocked=T|DatabaseDatalinksLocked=T
|RECORD=46|OwnerIndex=2596
|RECORD=48|OwnerIndex=2596
|RECORD=45|OwnerIndex=2595|IndexInSheet=-1|UseComponentLibrary=T|ModelName=FP-0603-L_1_6_0_2-W_0_8_0-IPC_B|ModelType=PCBLIB|DatafileCount=1|ModelDatafileEntity0=FP-0603-L_1_6_0_2-W_0_8_0-IPC_B|ModelDatafileKind0=PCBLib|DatalinksLocked=T|DatabaseDatalinksLocked=T
|RECORD=46|OwnerIndex=2599
|RECORD=48|OwnerIndex=2599
|RECORD=45|OwnerIndex=2595|IndexInSheet=-1|UseComponentLibrary=T|ModelName=FP-0603-L_1_6_0_2-W_0_8_0-IPC_C|ModelType=PCBLIB|DatafileCount=1|ModelDatafileEntity0=FP-0603-L_1_6_0_2-W_0_8_0-IPC_C|ModelDatafileKind0=PCBLib|DatalinksLocked=T|DatabaseDatalinksLocked=T
|RECORD=46|OwnerIndex=2602
|RECORD=48|OwnerIndex=2602
|RECORD=45|OwnerIndex=2595|IndexInSheet=-1|UseComponentLibrary=T|ModelName=FP-0603-L_1_6_0_2-W_0_8_0-IPC_A|ModelType=PCBLIB|DatafileCount=1|ModelDatafileEntity0=FP-0603-L_1_6_0_2-W_0_8_0-IPC_A|ModelDatafileKind0=PCBLib|DatalinksLocked=T|DatabaseDatalinksLocked=T
|RECORD=46|OwnerIndex=2605
|RECORD=48|OwnerIndex=2605
|RECORD=1|LibReference=b4654b650e69147ec39a6b967a45e02|ComponentDescription=Multilayer Ceramic Capacitors 2.2µF ±10% 16V X5R SMD 0402|PartCount=2|DisplayModeCount=1|IndexInSheet=215|OwnerPartId=-1|Location.X=1280|Location.Y=670|CurrentPartId=1|LibraryPath=*|SourceLibraryName=Altium Content Vault|TargetFileName=*|AreaColor=11599871|Color=128|PartIDLocked=T|DesignItemId=CMP-2000-05998-2|AllPinCount=2
|RECORD=2|OwnerIndex=2608|OwnerPartId=1|Electrical=4|PinConglomerate=49|PinLength=7|Location.X=1280|Location.Y=663|Name=1|Designator=1|PinPropagationDelay=0.000000E+000
|RECORD=2|OwnerIndex=2608|OwnerPartId=1|Electrical=4|PinConglomerate=51|PinLength=6|Location.X=1280|Location.Y=656|Name=2|Designator=2|PinPropagationDelay=0.000000E+000
|RECORD=13|OwnerIndex=2608|IsNotAccesible=T|IndexInSheet=2|OwnerPartId=1|Location.X=1290|Location.Y=663|Corner.X=1270|Corner.Y=663|LineWidth=1|Color=16711680
|RECORD=13|OwnerIndex=2608|IsNotAccesible=T|IndexInSheet=3|OwnerPartId=1|Location.X=1290|Location.Y=657|Corner.X=1270|Corner.Y=657|LineWidth=1|Color=16711680
|RECORD=13|OwnerIndex=2608|IsNotAccesible=T|IndexInSheet=4|OwnerPartId=1|Location.X=1280|Location.Y=663|Corner.X=1280|Corner.Y=666|LineWidth=1|Color=16711680
|RECORD=13|OwnerIndex=2608|IsNotAccesible=T|IndexInSheet=5|OwnerPartId=1|Location.X=1280|Location.Y=656|Corner.X=1280|Corner.Y=655|LineWidth=1|Color=16711680
|RECORD=41|OwnerIndex=2608|IndexInSheet=6|OwnerPartId=-1|Location.X=1269|Location.Y=672|Color=8388608|FontID=1|IsHidden=T|Text=No SVHC|Name=REACH SVHC
|RECORD=41|OwnerIndex=2608|IndexInSheet=7|OwnerPartId=-1|Location.X=1269|Location.Y=672|Color=8388608|FontID=1|IsHidden=T|Text=C|Name=Series
|RECORD=41|OwnerIndex=2608|IndexInSheet=8|OwnerPartId=-1|Location.X=1269|Location.Y=672|Color=8388608|FontID=1|IsHidden=T|Text=SMD/SMT|Name=Termination
|RECORD=41|OwnerIndex=2608|IndexInSheet=9|OwnerPartId=-1|Location.X=1269|Location.Y=672|Color=8388608|FontID=1|IsHidden=T|Text=0402|Name=Case Code (Imperial)
|RECORD=41|OwnerIndex=2608|IndexInSheet=10|OwnerPartId=-1|Location.X=1269|Location.Y=672|Color=8388608|FontID=1|IsHidden=T|Text=0.5mm|Name=Depth
|RECORD=41|OwnerIndex=2608|IndexInSheet=11|OwnerPartId=-1|Location.X=1269|Location.Y=672|Color=8388608|FontID=1|IsHidden=T|Text=Surface Mount|Name=Mount
|RECORD=41|OwnerIndex=2608|IndexInSheet=12|OwnerPartId=-1|Location.X=1269|Location.Y=672|Color=8388608|FontID=1|IsHidden=T|Text=0.02inch|Name=Width
|RECORD=41|OwnerIndex=2608|IndexInSheet=13|OwnerPartId=-1|Location.X=1269|Location.Y=672|Color=8388608|FontID=1|IsHidden=T|Text=1|Name=Package Quantity
|RECORD=41|OwnerIndex=2608|IndexInSheet=14|OwnerPartId=-1|Location.X=1269|Location.Y=672|Color=8388608|FontID=1|IsHidden=T|Text=Ceramic|Name=Dielectric Material
|RECORD=41|OwnerIndex=2608|IndexInSheet=15|OwnerPartId=-1|Location.X=1269|Location.Y=672|Color=8388608|FontID=1|IsHidden=T|Text=1mm|Name=Length
|RECORD=41|OwnerIndex=2608|IndexInSheet=16|OwnerPartId=-1|Location.X=1269|Location.Y=672|Color=8388608|FontID=1|IsHidden=T|Text=Tape and Reel|Name=Packaging
|RECORD=41|OwnerIndex=2608|IndexInSheet=17|OwnerPartId=-1|Location.X=1269|Location.Y=672|Color=8388608|FontID=1|IsHidden=T|Text=1005|Name=Case Code (Metric)
|RECORD=41|OwnerIndex=2608|IndexInSheet=18|OwnerPartId=-1|Location.X=1269|Location.Y=672|Color=8388608|FontID=1|IsHidden=T|Text=Yes|Name=RoHS Compliant
|RECORD=41|OwnerIndex=2608|IndexInSheet=19|OwnerPartId=-1|Location.X=1269|Location.Y=672|Color=8388608|FontID=1|IsHidden=T|Text=X5R|Name=Dielectric
|RECORD=41|OwnerIndex=2608|IndexInSheet=20|OwnerPartId=-1|Location.X=1269|Location.Y=672|Color=8388608|FontID=1|IsHidden=T|Text=85°C|Name=Max Operating Temperature
|RECORD=41|OwnerIndex=2608|IndexInSheet=21|OwnerPartId=-1|Location.X=1269|Location.Y=672|Color=8388608|FontID=1|IsHidden=T|Text=Lead Free|Name=Lead Free
|RECORD=41|OwnerIndex=2608|IndexInSheet=22|OwnerPartId=-1|Location.X=1269|Location.Y=672|Color=8388608|FontID=1|IsHidden=T|Text=2.3E-05oz|Name=Weight
|RECORD=41|OwnerIndex=2608|IndexInSheet=23|OwnerPartId=-1|Location.X=1269|Location.Y=672|Color=8388608|FontID=1|IsHidden=T|Text=0.022inch|Name=Thickness
|RECORD=41|OwnerIndex=2608|IndexInSheet=24|OwnerPartId=-1|Location.X=1269|Location.Y=672|Color=8388608|FontID=1|IsHidden=T|Text=2.2uF|Name=Capacitance
|RECORD=41|OwnerIndex=2608|IndexInSheet=25|OwnerPartId=-1|Location.X=1269|Location.Y=672|Color=8388608|FontID=1|IsHidden=T|Text=16V|Name=Voltage Rating (DC)
|RECORD=41|OwnerIndex=2608|IndexInSheet=26|OwnerPartId=-1|Location.X=1269|Location.Y=672|Color=8388608|FontID=1|IsHidden=T|Text=10%|Name=Tolerance
|RECORD=41|OwnerIndex=2608|IndexInSheet=27|OwnerPartId=-1|Location.X=1269|Location.Y=672|Color=8388608|FontID=1|IsHidden=T|Text=16V|Name=Voltage Rating
|RECORD=41|OwnerIndex=2608|IndexInSheet=28|OwnerPartId=-1|Location.X=1269|Location.Y=672|Color=8388608|FontID=1|IsHidden=T|Text=Ceramic|Name=Resistor Type
|RECORD=41|OwnerIndex=2608|IndexInSheet=29|OwnerPartId=-1|Location.X=1269|Location.Y=672|Color=8388608|FontID=1|IsHidden=T|Text=0.5mm|Name=Height
|RECORD=41|OwnerIndex=2608|IndexInSheet=30|OwnerPartId=-1|Location.X=1269|Location.Y=672|Color=8388608|FontID=1|IsHidden=T|Text=0402|Name=Case/Package
|RECORD=41|OwnerIndex=2608|IndexInSheet=31|OwnerPartId=-1|Location.X=1269|Location.Y=672|Color=8388608|FontID=1|IsHidden=T|Text=-55°C|Name=Min Operating Temperature
|RECORD=34|OwnerIndex=2608|IndexInSheet=-1|OwnerPartId=-1|Location.X=1270|Location.Y=650|Orientation=1|Color=8388608|FontID=2|Text=C9|Name=Designator|ReadOnlyState=1
|RECORD=41|OwnerIndex=2608|IndexInSheet=-1|OwnerPartId=1|Location.X=1300|Location.Y=625|Orientation=1|Color=8388608|FontID=2|Text=2.2uF_16V_0402|Name=Comment
|RECORD=44|OwnerIndex=2608
|RECORD=45|OwnerIndex=2645|IndexInSheet=-1|UseComponentLibrary=T|ModelName=FP-C1005-050-0_05-IPC_A|ModelType=PCBLIB|DatafileCount=1|ModelDatafileEntity0=FP-C1005-050-0_05-IPC_A|ModelDatafileKind0=PCBLib|IsCurrent=T|DatalinksLocked=T|DatabaseDatalinksLocked=T
|RECORD=46|OwnerIndex=2646
|RECORD=48|OwnerIndex=2646
|RECORD=45|OwnerIndex=2645|IndexInSheet=-1|UseComponentLibrary=T|ModelName=FP-C1005-050-0_05-MFG|ModelType=PCBLIB|DatafileCount=1|ModelDatafileEntity0=FP-C1005-050-0_05-MFG|ModelDatafileKind0=PCBLib|DatalinksLocked=T|DatabaseDatalinksLocked=T
|RECORD=46|OwnerIndex=2649
|RECORD=48|OwnerIndex=2649
|RECORD=45|OwnerIndex=2645|IndexInSheet=-1|UseComponentLibrary=T|ModelName=FP-C1005-050-0_05-IPC_C|ModelType=PCBLIB|DatafileCount=1|ModelDatafileEntity0=FP-C1005-050-0_05-IPC_C|ModelDatafileKind0=PCBLib|DatalinksLocked=T|DatabaseDatalinksLocked=T
|RECORD=46|OwnerIndex=2652
|RECORD=48|OwnerIndex=2652
|RECORD=45|OwnerIndex=2645|IndexInSheet=-1|UseComponentLibrary=T|ModelName=FP-C1005-050-0_05-IPC_B|ModelType=PCBLIB|DatafileCount=1|ModelDatafileEntity0=FP-C1005-050-0_05-IPC_B|ModelDatafileKind0=PCBLib|DatalinksLocked=T|DatabaseDatalinksLocked=T
|RECORD=46|OwnerIndex=2655
|RECORD=48|OwnerIndex=2655
|RECORD=1|LibReference=b4654b650e69147ec39a6b967a45e02|ComponentDescription=None|PartCount=2|DisplayModeCount=1|IndexInSheet=216|OwnerPartId=-1|Location.X=1325|Location.Y=670|CurrentPartId=1|LibraryPath=*|SourceLibraryName=Altium Content Vault|TargetFileName=*|AreaColor=11599871|Color=128|PartIDLocked=T|DesignItemId=CMP-14477-000104-2|AllPinCount=2
|RECORD=2|OwnerIndex=2658|OwnerPartId=1|Electrical=4|PinConglomerate=49|PinLength=7|Location.X=1325|Location.Y=663|Name=1|Designator=1|PinPropagationDelay=0.000000E+000
|RECORD=2|OwnerIndex=2658|OwnerPartId=1|Electrical=4|PinConglomerate=51|PinLength=6|Location.X=1325|Location.Y=656|Name=2|Designator=2|PinPropagationDelay=0.000000E+000
|RECORD=13|OwnerIndex=2658|IsNotAccesible=T|IndexInSheet=2|OwnerPartId=1|Location.X=1335|Location.Y=663|Corner.X=1315|Corner.Y=663|LineWidth=1|Color=16711680
|RECORD=13|OwnerIndex=2658|IsNotAccesible=T|IndexInSheet=3|OwnerPartId=1|Location.X=1335|Location.Y=657|Corner.X=1315|Corner.Y=657|LineWidth=1|Color=16711680
|RECORD=13|OwnerIndex=2658|IsNotAccesible=T|IndexInSheet=4|OwnerPartId=1|Location.X=1325|Location.Y=663|Corner.X=1325|Corner.Y=666|LineWidth=1|Color=16711680
|RECORD=13|OwnerIndex=2658|IsNotAccesible=T|IndexInSheet=5|OwnerPartId=1|Location.X=1325|Location.Y=656|Corner.X=1325|Corner.Y=655|LineWidth=1|Color=16711680
|RECORD=41|OwnerIndex=2658|IndexInSheet=6|OwnerPartId=-1|Location.X=1314|Location.Y=672|Color=8388608|FontID=1|IsHidden=T|Text=Tape and Reel|Name=Packaging
|RECORD=41|OwnerIndex=2658|IndexInSheet=7|OwnerPartId=-1|Location.X=1314|Location.Y=672|Color=8388608|FontID=1|IsHidden=T|Text=0.5mm|Name=Depth
|RECORD=41|OwnerIndex=2658|IndexInSheet=8|OwnerPartId=-1|Location.X=1314|Location.Y=672|Color=8388608|FontID=1|IsHidden=T|Text=10%|Name=Tolerance
|RECORD=41|OwnerIndex=2658|IndexInSheet=9|OwnerPartId=-1|Location.X=1314|Location.Y=672|Color=8388608|FontID=1|IsHidden=T|Text=Surface Mount|Name=Mount
|RECORD=41|OwnerIndex=2658|IndexInSheet=10|OwnerPartId=-1|Location.X=1314|Location.Y=672|Color=8388608|FontID=1|IsHidden=T|Text=16V|Name=Voltage Rating
|RECORD=41|OwnerIndex=2658|IndexInSheet=11|OwnerPartId=-1|Location.X=1314|Location.Y=672|Color=8388608|FontID=1|IsHidden=T|Text=0.022inch|Name=Thickness
|RECORD=41|OwnerIndex=2658|IndexInSheet=12|OwnerPartId=-1|Location.X=1314|Location.Y=672|Color=8388608|FontID=1|IsHidden=T|Text=1|Name=Package Quantity
|RECORD=41|OwnerIndex=2658|IndexInSheet=13|OwnerPartId=-1|Location.X=1314|Location.Y=672|Color=8388608|FontID=1|IsHidden=T|Text=-55°C|Name=Min Operating Temperature
|RECORD=41|OwnerIndex=2658|IndexInSheet=14|OwnerPartId=-1|Location.X=1314|Location.Y=672|Color=8388608|FontID=1|IsHidden=T|Text=M|Name=Series
|RECORD=41|OwnerIndex=2658|IndexInSheet=15|OwnerPartId=-1|Location.X=1314|Location.Y=672|Color=8388608|FontID=1|IsHidden=T|Text=16V|Name=Voltage Rating (DC)
|RECORD=41|OwnerIndex=2658|IndexInSheet=16|OwnerPartId=-1|Location.X=1314|Location.Y=672|Color=8388608|FontID=1|IsHidden=T|Text=SMD/SMT|Name=Termination
|RECORD=41|OwnerIndex=2658|IndexInSheet=17|OwnerPartId=-1|Location.X=1314|Location.Y=672|Color=8388608|FontID=1|IsHidden=T|Text=0402|Name=Case/Package
|RECORD=41|OwnerIndex=2658|IndexInSheet=18|OwnerPartId=-1|Location.X=1314|Location.Y=672|Color=8388608|FontID=1|IsHidden=T|Text=X5R|Name=Dielectric
|RECORD=41|OwnerIndex=2658|IndexInSheet=19|OwnerPartId=-1|Location.X=1314|Location.Y=672|Color=8388608|FontID=1|IsHidden=T|Text=2|Name=Number of Pins
|RECORD=41|OwnerIndex=2658|IndexInSheet=20|OwnerPartId=-1|Location.X=1314|Location.Y=672|Color=8388608|FontID=1|IsHidden=T|Text=0402|Name=Case Code (Imperial)
|RECORD=41|OwnerIndex=2658|IndexInSheet=21|OwnerPartId=-1|Location.X=1314|Location.Y=672|Color=8388608|FontID=1|IsHidden=T|Text=1uF|Name=Capacitance
|RECORD=41|OwnerIndex=2658|IndexInSheet=22|OwnerPartId=-1|Location.X=1314|Location.Y=672|Color=8388608|FontID=1|IsHidden=T|Text=1mm|Name=Length
|RECORD=41|OwnerIndex=2658|IndexInSheet=23|OwnerPartId=-1|Location.X=1314|Location.Y=672|Color=8388608|FontID=1|IsHidden=T|Text=Halogen Free|Name=Halogen Free
|RECORD=41|OwnerIndex=2658|IndexInSheet=24|OwnerPartId=-1|Location.X=1314|Location.Y=672|Color=8388608|FontID=1|IsHidden=T|Text=1005|Name=Case Code (Metric)
|RECORD=41|OwnerIndex=2658|IndexInSheet=25|OwnerPartId=-1|Location.X=1314|Location.Y=672|Color=8388608|FontID=1|IsHidden=T|Text=0.02inch|Name=Width
|RECORD=41|OwnerIndex=2658|IndexInSheet=26|OwnerPartId=-1|Location.X=1314|Location.Y=672|Color=8388608|FontID=1|IsHidden=T|Text=Yes|Name=RoHS Compliant
|RECORD=41|OwnerIndex=2658|IndexInSheet=27|OwnerPartId=-1|Location.X=1314|Location.Y=672|Color=8388608|FontID=1|IsHidden=T|Text=No|Name=Radiation Hardening
|RECORD=41|OwnerIndex=2658|IndexInSheet=28|OwnerPartId=-1|Location.X=1314|Location.Y=672|Color=8388608|FontID=1|IsHidden=T|Text=85°C|Name=Max Operating Temperature
|RECORD=41|OwnerIndex=2658|IndexInSheet=29|OwnerPartId=-1|Location.X=1314|Location.Y=672|Color=8388608|FontID=1|IsHidden=T|Text=0.5mm|Name=Height
|RECORD=41|OwnerIndex=2658|IndexInSheet=30|OwnerPartId=-1|Location.X=1314|Location.Y=672|Color=8388608|FontID=1|IsHidden=T|Text=Flat|Name=Construction
|RECORD=34|OwnerIndex=2658|IndexInSheet=-1|OwnerPartId=-1|Location.X=1310|Location.Y=650|Orientation=1|Color=8388608|FontID=2|Text=C32|Name=Designator|ReadOnlyState=1
|RECORD=41|OwnerIndex=2658|IndexInSheet=-1|OwnerPartId=1|Location.X=1345|Location.Y=635|Orientation=1|Color=8388608|FontID=2|Text=1uF_16V_0402|Name=Comment
|RECORD=44|OwnerIndex=2658
|RECORD=45|OwnerIndex=2694|IndexInSheet=-1|UseComponentLibrary=T|ModelName=FP-0402-L_1_0_0_05-W_0_5-IPC_A|ModelType=PCBLIB|DatafileCount=1|ModelDatafileEntity0=FP-0402-L_1_0_0_05-W_0_5-IPC_A|ModelDatafileKind0=PCBLib|IsCurrent=T|DatalinksLocked=T|DatabaseDatalinksLocked=T
|RECORD=46|OwnerIndex=2695
|RECORD=48|OwnerIndex=2695
|RECORD=45|OwnerIndex=2694|IndexInSheet=-1|UseComponentLibrary=T|ModelName=EMK105BJ105_V-F|ModelType=SIM|IsCurrent=T|DatalinksLocked=T|DatabaseDatalinksLocked=T
|RECORD=46|OwnerIndex=2698
|RECORD=48|OwnerIndex=2698
|RECORD=41|OwnerIndex=2700|IndexInSheet=-1|OwnerPartId=-1|Color=8388608|FontID=1|IsHidden=T|Text=General|Name=Kind
|RECORD=41|OwnerIndex=2700|IndexInSheet=-1|OwnerPartId=-1|Color=8388608|FontID=1|IsHidden=T|Text=Spice Subcircuit|Name=SubKind
|RECORD=41|OwnerIndex=2700|IndexInSheet=-1|OwnerPartId=-1|Color=8388608|FontID=1|IsHidden=T|Name=Spice Prefix
|RECORD=41|OwnerIndex=2700|IndexInSheet=-1|OwnerPartId=-1|Color=8388608|FontID=1|IsHidden=T|Name=Excluded Parts
|RECORD=41|OwnerIndex=2700|IndexInSheet=-1|OwnerPartId=-1|Color=8388608|FontID=1|IsHidden=T|Name=Netlist
|RECORD=41|OwnerIndex=2700|IndexInSheet=-1|OwnerPartId=-1|Color=8388608|FontID=1|IsHidden=T|Text=document_sim_cache\YSTRYKDD\0|Name=SimulationCacheLocation|ReadOnlyState=3
|RECORD=45|OwnerIndex=2694|IndexInSheet=-1|UseComponentLibrary=T|ModelName=FP-0402-L_1_0_0_05-W_0_5-IPC_B|ModelType=PCBLIB|DatafileCount=1|ModelDatafileEntity0=FP-0402-L_1_0_0_05-W_0_5-IPC_B|ModelDatafileKind0=PCBLib|DatalinksLocked=T|DatabaseDatalinksLocked=T
|RECORD=46|OwnerIndex=2707
|RECORD=48|OwnerIndex=2707
|RECORD=45|OwnerIndex=2694|IndexInSheet=-1|UseComponentLibrary=T|ModelName=FP-0402-L_1_0_0_05-W_0_5-IPC_C|ModelType=PCBLIB|DatafileCount=1|ModelDatafileEntity0=FP-0402-L_1_0_0_05-W_0_5-IPC_C|ModelDatafileKind0=PCBLib|DatalinksLocked=T|DatabaseDatalinksLocked=T
|RECORD=46|OwnerIndex=2710
|RECORD=48|OwnerIndex=2710
|RECORD=45|OwnerIndex=2694|IndexInSheet=-1|UseComponentLibrary=T|ModelName=FP-0402-L_1_0_0_05-W_0_5-MFG|ModelType=PCBLIB|DatafileCount=1|ModelDatafileEntity0=FP-0402-L_1_0_0_05-W_0_5-MFG|ModelDatafileKind0=PCBLib|DatalinksLocked=T|DatabaseDatalinksLocked=T
|RECORD=46|OwnerIndex=2713
|RECORD=48|OwnerIndex=2713
|RECORD=1|LibReference=b4654b650e69147ec39a6b967a45e02|ComponentDescription=General Purpose Ceramic Capacitor, 0402, 100nF, 10%, X7R, 15%, 25V|PartCount=2|DisplayModeCount=1|IndexInSheet=217|OwnerPartId=-1|Location.X=1365|Location.Y=670|CurrentPartId=1|LibraryPath=*|SourceLibraryName=Altium Content Vault|TargetFileName=*|AreaColor=11599871|Color=128|PartIDLocked=T|DesignItemId=CMP-2008-02519-2|AllPinCount=2
|RECORD=2|OwnerIndex=2716|OwnerPartId=1|Electrical=4|PinConglomerate=49|PinLength=7|Location.X=1365|Location.Y=663|Name=1|Designator=1|PinPropagationDelay=0.000000E+000
|RECORD=2|OwnerIndex=2716|OwnerPartId=1|Electrical=4|PinConglomerate=51|PinLength=6|Location.X=1365|Location.Y=656|Name=2|Designator=2|PinPropagationDelay=0.000000E+000
|RECORD=13|OwnerIndex=2716|IsNotAccesible=T|IndexInSheet=2|OwnerPartId=1|Location.X=1375|Location.Y=663|Corner.X=1355|Corner.Y=663|LineWidth=1|Color=16711680
|RECORD=13|OwnerIndex=2716|IsNotAccesible=T|IndexInSheet=3|OwnerPartId=1|Location.X=1375|Location.Y=657|Corner.X=1355|Corner.Y=657|LineWidth=1|Color=16711680
|RECORD=13|OwnerIndex=2716|IsNotAccesible=T|IndexInSheet=4|OwnerPartId=1|Location.X=1365|Location.Y=663|Corner.X=1365|Corner.Y=666|LineWidth=1|Color=16711680
|RECORD=13|OwnerIndex=2716|IsNotAccesible=T|IndexInSheet=5|OwnerPartId=1|Location.X=1365|Location.Y=656|Corner.X=1365|Corner.Y=655|LineWidth=1|Color=16711680
|RECORD=41|OwnerIndex=2716|IndexInSheet=6|OwnerPartId=-1|Location.X=1354|Location.Y=672|Color=8388608|FontID=1|IsHidden=T|Text=1|Name=Package Quantity
|RECORD=41|OwnerIndex=2716|IndexInSheet=7|OwnerPartId=-1|Location.X=1354|Location.Y=672|Color=8388608|FontID=1|IsHidden=T|Text=100nF|Name=Capacitance
|RECORD=41|OwnerIndex=2716|IndexInSheet=8|OwnerPartId=-1|Location.X=1354|Location.Y=672|Color=8388608|FontID=1|IsHidden=T|Text=-55°C|Name=Min Operating Temperature
|RECORD=41|OwnerIndex=2716|IndexInSheet=9|OwnerPartId=-1|Location.X=1354|Location.Y=672|Color=8388608|FontID=1|IsHidden=T|Text=25V|Name=Voltage
|RECORD=41|OwnerIndex=2716|IndexInSheet=10|OwnerPartId=-1|Location.X=1354|Location.Y=672|Color=8388608|FontID=1|IsHidden=T|Text=25V|Name=Voltage Rating
|RECORD=41|OwnerIndex=2716|IndexInSheet=11|OwnerPartId=-1|Location.X=1354|Location.Y=672|Color=8388608|FontID=1|IsHidden=T|Text=Flat|Name=Construction
|RECORD=41|OwnerIndex=2716|IndexInSheet=12|OwnerPartId=-1|Location.X=1354|Location.Y=672|Color=8388608|FontID=1|IsHidden=T|Text=125°C|Name=Max Operating Temperature
|RECORD=41|OwnerIndex=2716|IndexInSheet=13|OwnerPartId=-1|Location.X=1354|Location.Y=672|Color=8388608|FontID=1|IsHidden=T|Text=No|Name=Radiation Hardening
|RECORD=41|OwnerIndex=2716|IndexInSheet=14|OwnerPartId=-1|Location.X=1354|Location.Y=672|Color=8388608|FontID=1|IsHidden=T|Text=0.5mm|Name=Depth
|RECORD=41|OwnerIndex=2716|IndexInSheet=15|OwnerPartId=-1|Location.X=1354|Location.Y=672|Color=8388608|FontID=1|IsHidden=T|Text=0.022inch|Name=Thickness
|RECORD=41|OwnerIndex=2716|IndexInSheet=16|OwnerPartId=-1|Location.X=1354|Location.Y=672|Color=8388608|FontID=1|IsHidden=T|Text=25V|Name=Voltage Rating (DC)
|RECORD=41|OwnerIndex=2716|IndexInSheet=17|OwnerPartId=-1|Location.X=1354|Location.Y=672|Color=8388608|FontID=1|IsHidden=T|Text=2|Name=Number of Pins
|RECORD=41|OwnerIndex=2716|IndexInSheet=18|OwnerPartId=-1|Location.X=1354|Location.Y=672|Color=8388608|FontID=1|IsHidden=T|Text=Lead Free|Name=Lead Free
|RECORD=41|OwnerIndex=2716|IndexInSheet=19|OwnerPartId=-1|Location.X=1354|Location.Y=672|Color=8388608|FontID=1|IsHidden=T|Text=-|Name=Series
|RECORD=41|OwnerIndex=2716|IndexInSheet=20|OwnerPartId=-1|Location.X=1354|Location.Y=672|Color=8388608|FontID=1|IsHidden=T|Text=No SVHC|Name=REACH SVHC
|RECORD=41|OwnerIndex=2716|IndexInSheet=21|OwnerPartId=-1|Location.X=1354|Location.Y=672|Color=8388608|FontID=1|IsHidden=T|Text=1mm|Name=Length
|RECORD=41|OwnerIndex=2716|IndexInSheet=22|OwnerPartId=-1|Location.X=1354|Location.Y=672|Color=8388608|FontID=1|IsHidden=T|Text=X7R|Name=Dielectric
|RECORD=41|OwnerIndex=2716|IndexInSheet=23|OwnerPartId=-1|Location.X=1354|Location.Y=672|Color=8388608|FontID=1|IsHidden=T|Text=Yes|Name=RoHS Compliant
|RECORD=41|OwnerIndex=2716|IndexInSheet=24|OwnerPartId=-1|Location.X=1354|Location.Y=672|Color=8388608|FontID=1|IsHidden=T|Text=Surface Mount|Name=Mount
|RECORD=41|OwnerIndex=2716|IndexInSheet=25|OwnerPartId=-1|Location.X=1354|Location.Y=672|Color=8388608|FontID=1|IsHidden=T|Text=Tape and Reel|Name=Packaging
|RECORD=41|OwnerIndex=2716|IndexInSheet=26|OwnerPartId=-1|Location.X=1354|Location.Y=672|Color=8388608|FontID=1|IsHidden=T|Text=0402|Name=Case/Package
|RECORD=41|OwnerIndex=2716|IndexInSheet=27|OwnerPartId=-1|Location.X=1354|Location.Y=672|Color=8388608|FontID=1|IsHidden=T|Text=0402|Name=Case Code (Imperial)
|RECORD=41|OwnerIndex=2716|IndexInSheet=28|OwnerPartId=-1|Location.X=1354|Location.Y=672|Color=8388608|FontID=1|IsHidden=T|Text=SMD/SMT|Name=Termination
|RECORD=41|OwnerIndex=2716|IndexInSheet=29|OwnerPartId=-1|Location.X=1354|Location.Y=672|Color=8388608|FontID=1|IsHidden=T|Text=0.02inch|Name=Width
|RECORD=41|OwnerIndex=2716|IndexInSheet=30|OwnerPartId=-1|Location.X=1354|Location.Y=672|Color=8388608|FontID=1|IsHidden=T|Text=1005|Name=Case Code (Metric)
|RECORD=41|OwnerIndex=2716|IndexInSheet=31|OwnerPartId=-1|Location.X=1354|Location.Y=672|Color=8388608|FontID=1|IsHidden=T|Text=10%|Name=Tolerance
|RECORD=34|OwnerIndex=2716|IndexInSheet=-1|OwnerPartId=-1|Location.X=1355|Location.Y=650|Orientation=1|Color=8388608|FontID=2|Text=C33|Name=Designator|ReadOnlyState=1
|RECORD=41|OwnerIndex=2716|IndexInSheet=-1|OwnerPartId=1|Location.X=1385|Location.Y=635|Orientation=1|Color=8388608|FontID=2|Text=0.1uF_25V_0402|Name=Comment
|RECORD=44|OwnerIndex=2716
|RECORD=45|OwnerIndex=2753|IndexInSheet=-1|UseComponentLibrary=T|ModelName=FP-0402-L_1_0_1-W_0_5_0_1-IPC_C|ModelType=PCBLIB|DatafileCount=1|ModelDatafileEntity0=FP-0402-L_1_0_1-W_0_5_0_1-IPC_C|ModelDatafileKind0=PCBLib|IsCurrent=T|DatalinksLocked=T|DatabaseDatalinksLocked=T
|RECORD=46|OwnerIndex=2754
|RECORD=48|OwnerIndex=2754
|RECORD=45|OwnerIndex=2753|IndexInSheet=-1|UseComponentLibrary=T|ModelName=FP-0402-L_1_0_1-W_0_5_0_1-IPC_B|ModelType=PCBLIB|DatafileCount=1|ModelDatafileEntity0=FP-0402-L_1_0_1-W_0_5_0_1-IPC_B|ModelDatafileKind0=PCBLib|DatalinksLocked=T|DatabaseDatalinksLocked=T
|RECORD=46|OwnerIndex=2757
|RECORD=48|OwnerIndex=2757
|RECORD=45|OwnerIndex=2753|IndexInSheet=-1|UseComponentLibrary=T|ModelName=FP-0402-L_1_0_1-W_0_5_0_1-MFG|ModelType=PCBLIB|DatafileCount=1|ModelDatafileEntity0=FP-0402-L_1_0_1-W_0_5_0_1-MFG|ModelDatafileKind0=PCBLib|DatalinksLocked=T|DatabaseDatalinksLocked=T
|RECORD=46|OwnerIndex=2760
|RECORD=48|OwnerIndex=2760
|RECORD=45|OwnerIndex=2753|IndexInSheet=-1|UseComponentLibrary=T|ModelName=FP-0402-L_1_0_1-W_0_5_0_1-IPC_A|ModelType=PCBLIB|DatafileCount=1|ModelDatafileEntity0=FP-0402-L_1_0_1-W_0_5_0_1-IPC_A|ModelDatafileKind0=PCBLib|DatalinksLocked=T|DatabaseDatalinksLocked=T
|RECORD=46|OwnerIndex=2763
|RECORD=48|OwnerIndex=2763
|RECORD=17|IndexInSheet=218|OwnerPartId=-1|ShowNetName=T|Location.X=1010|Location.Y=740|Orientation=1|Color=128|FontID=1|Text=+5.0V
|RECORD=1|LibReference=b4654b650e69147ec39a6b967a45e02|ComponentDescription=Multilayer Ceramic Capacitor 10uF 16V X5R 20% SMD 0603 T/R|PartCount=2|DisplayModeCount=1|IndexInSheet=219|OwnerPartId=-1|Location.X=1005|Location.Y=680|CurrentPartId=1|LibraryPath=*|SourceLibraryName=Altium Content Vault|TargetFileName=*|AreaColor=11599871|Color=128|PartIDLocked=T|DesignItemId=CMP-2000-06226-4|AllPinCount=2
|RECORD=2|OwnerIndex=2767|OwnerPartId=1|Electrical=4|PinConglomerate=49|PinLength=7|Location.X=1005|Location.Y=673|Name=1|Designator=1|PinPropagationDelay=0.000000E+000
|RECORD=2|OwnerIndex=2767|OwnerPartId=1|Electrical=4|PinConglomerate=51|PinLength=6|Location.X=1005|Location.Y=666|Name=2|Designator=2|PinPropagationDelay=0.000000E+000
|RECORD=13|OwnerIndex=2767|IsNotAccesible=T|IndexInSheet=2|OwnerPartId=1|Location.X=1015|Location.Y=673|Corner.X=995|Corner.Y=673|LineWidth=1|Color=16711680
|RECORD=13|OwnerIndex=2767|IsNotAccesible=T|IndexInSheet=3|OwnerPartId=1|Location.X=1015|Location.Y=667|Corner.X=995|Corner.Y=667|LineWidth=1|Color=16711680
|RECORD=13|OwnerIndex=2767|IsNotAccesible=T|IndexInSheet=4|OwnerPartId=1|Location.X=1005|Location.Y=673|Corner.X=1005|Corner.Y=676|LineWidth=1|Color=16711680
|RECORD=13|OwnerIndex=2767|IsNotAccesible=T|IndexInSheet=5|OwnerPartId=1|Location.X=1005|Location.Y=666|Corner.X=1005|Corner.Y=665|LineWidth=1|Color=16711680
|RECORD=41|OwnerIndex=2767|IndexInSheet=6|OwnerPartId=-1|Location.X=994|Location.Y=682|Color=8388608|FontID=1|IsHidden=T|Text=Tape and Reel|Name=Packaging
|RECORD=41|OwnerIndex=2767|IndexInSheet=7|OwnerPartId=-1|Location.X=994|Location.Y=682|Color=8388608|FontID=1|IsHidden=T|Text=Flat|Name=Construction
|RECORD=41|OwnerIndex=2767|IndexInSheet=8|OwnerPartId=-1|Location.X=994|Location.Y=682|Color=8388608|FontID=1|IsHidden=T|Text=0.8mm|Name=Height
|RECORD=41|OwnerIndex=2767|IndexInSheet=9|OwnerPartId=-1|Location.X=994|Location.Y=682|Color=8388608|FontID=1|IsHidden=T|Text=85°C|Name=Max Operating Temperature
|RECORD=41|OwnerIndex=2767|IndexInSheet=10|OwnerPartId=-1|Location.X=994|Location.Y=682|Color=8388608|FontID=1|IsHidden=T|Text=X5R|Name=Dielectric
|RECORD=41|OwnerIndex=2767|IndexInSheet=11|OwnerPartId=-1|Location.X=994|Location.Y=682|Color=8388608|FontID=1|IsHidden=T|Text=1608|Name=Case Code (Metric)
|RECORD=41|OwnerIndex=2767|IndexInSheet=12|OwnerPartId=-1|Location.X=994|Location.Y=682|Color=8388608|FontID=1|IsHidden=T|Text=16V|Name=Voltage Rating (DC)
|RECORD=41|OwnerIndex=2767|IndexInSheet=13|OwnerPartId=-1|Location.X=994|Location.Y=682|Color=8388608|FontID=1|IsHidden=T|Text=0.031inch|Name=Width
|RECORD=41|OwnerIndex=2767|IndexInSheet=14|OwnerPartId=-1|Location.X=994|Location.Y=682|Color=8388608|FontID=1|IsHidden=T|Text=16V|Name=Voltage Rating
|RECORD=41|OwnerIndex=2767|IndexInSheet=15|OwnerPartId=-1|Location.X=994|Location.Y=682|Color=8388608|FontID=1|IsHidden=T|Text=0.063inch|Name=Length
|RECORD=41|OwnerIndex=2767|IndexInSheet=16|OwnerPartId=-1|Location.X=994|Location.Y=682|Color=8388608|FontID=1|IsHidden=T|Text=Yes|Name=RoHS Compliant
|RECORD=41|OwnerIndex=2767|IndexInSheet=17|OwnerPartId=-1|Location.X=994|Location.Y=682|Color=8388608|FontID=1|IsHidden=T|Text=Halogen Free|Name=Halogen Free
|RECORD=41|OwnerIndex=2767|IndexInSheet=18|OwnerPartId=-1|Location.X=994|Location.Y=682|Color=8388608|FontID=1|IsHidden=T|Text=0603|Name=Case Code (Imperial)
|RECORD=41|OwnerIndex=2767|IndexInSheet=19|OwnerPartId=-1|Location.X=994|Location.Y=682|Color=8388608|FontID=1|IsHidden=T|Text=10uF|Name=Capacitance
|RECORD=41|OwnerIndex=2767|IndexInSheet=20|OwnerPartId=-1|Location.X=994|Location.Y=682|Color=8388608|FontID=1|IsHidden=T|Text=Surface Mount|Name=Mount
|RECORD=41|OwnerIndex=2767|IndexInSheet=21|OwnerPartId=-1|Location.X=994|Location.Y=682|Color=8388608|FontID=1|IsHidden=T|Text=0.031inch|Name=Thickness
|RECORD=41|OwnerIndex=2767|IndexInSheet=22|OwnerPartId=-1|Location.X=994|Location.Y=682|Color=8388608|FontID=1|IsHidden=T|Text=20%|Name=Tolerance
|RECORD=41|OwnerIndex=2767|IndexInSheet=23|OwnerPartId=-1|Location.X=994|Location.Y=682|Color=8388608|FontID=1|IsHidden=T|Text=-55°C|Name=Min Operating Temperature
|RECORD=41|OwnerIndex=2767|IndexInSheet=24|OwnerPartId=-1|Location.X=994|Location.Y=682|Color=8388608|FontID=1|IsHidden=T|Text=M|Name=Series
|RECORD=41|OwnerIndex=2767|IndexInSheet=25|OwnerPartId=-1|Location.X=994|Location.Y=682|Color=8388608|FontID=1|IsHidden=T|Text=SMD/SMT|Name=Termination
|RECORD=41|OwnerIndex=2767|IndexInSheet=26|OwnerPartId=-1|Location.X=994|Location.Y=682|Color=8388608|FontID=1|IsHidden=T|Text=0603|Name=Case/Package
|RECORD=41|OwnerIndex=2767|IndexInSheet=27|OwnerPartId=-1|Location.X=994|Location.Y=682|Color=8388608|FontID=1|IsHidden=T|Text=1|Name=Package Quantity
|RECORD=34|OwnerIndex=2767|IndexInSheet=-1|OwnerPartId=-1|Location.X=995|Location.Y=660|Orientation=1|Color=8388608|FontID=2|Text=C6|Name=Designator|ReadOnlyState=1
|RECORD=41|OwnerIndex=2767|IndexInSheet=-1|OwnerPartId=1|Location.X=1025|Location.Y=645|Orientation=1|Color=8388608|FontID=2|Text=10uF_16V_0603|Name=Comment
|RECORD=44|OwnerIndex=2767
|RECORD=45|OwnerIndex=2800|IndexInSheet=-1|UseComponentLibrary=T|ModelName=FP-0603-L_1_6_0_2-W_0_8_0-MFG|ModelType=PCBLIB|DatafileCount=1|ModelDatafileEntity0=FP-0603-L_1_6_0_2-W_0_8_0-MFG|ModelDatafileKind0=PCBLib|IsCurrent=T|DatalinksLocked=T|DatabaseDatalinksLocked=T
|RECORD=46|OwnerIndex=2801
|RECORD=48|OwnerIndex=2801
|RECORD=45|OwnerIndex=2800|IndexInSheet=-1|UseComponentLibrary=T|ModelName=FP-0603-L_1_6_0_2-W_0_8_0-IPC_B|ModelType=PCBLIB|DatafileCount=1|ModelDatafileEntity0=FP-0603-L_1_6_0_2-W_0_8_0-IPC_B|ModelDatafileKind0=PCBLib|DatalinksLocked=T|DatabaseDatalinksLocked=T
|RECORD=46|OwnerIndex=2804
|RECORD=48|OwnerIndex=2804
|RECORD=45|OwnerIndex=2800|IndexInSheet=-1|UseComponentLibrary=T|ModelName=FP-0603-L_1_6_0_2-W_0_8_0-IPC_C|ModelType=PCBLIB|DatafileCount=1|ModelDatafileEntity0=FP-0603-L_1_6_0_2-W_0_8_0-IPC_C|ModelDatafileKind0=PCBLib|DatalinksLocked=T|DatabaseDatalinksLocked=T
|RECORD=46|OwnerIndex=2807
|RECORD=48|OwnerIndex=2807
|RECORD=45|OwnerIndex=2800|IndexInSheet=-1|UseComponentLibrary=T|ModelName=FP-0603-L_1_6_0_2-W_0_8_0-IPC_A|ModelType=PCBLIB|DatafileCount=1|ModelDatafileEntity0=FP-0603-L_1_6_0_2-W_0_8_0-IPC_A|ModelDatafileKind0=PCBLib|DatalinksLocked=T|DatabaseDatalinksLocked=T
|RECORD=46|OwnerIndex=2810
|RECORD=48|OwnerIndex=2810
|RECORD=1|LibReference=b4654b650e69147ec39a6b967a45e02|ComponentDescription=Multilayer Ceramic Capacitors 2.2µF ±10% 16V X5R SMD 0402|PartCount=2|DisplayModeCount=1|IndexInSheet=220|OwnerPartId=-1|Location.X=1050|Location.Y=680|CurrentPartId=1|LibraryPath=*|SourceLibraryName=Altium Content Vault|TargetFileName=*|AreaColor=11599871|Color=128|PartIDLocked=T|DesignItemId=CMP-2000-05998-2|AllPinCount=2
|RECORD=2|OwnerIndex=2813|OwnerPartId=1|Electrical=4|PinConglomerate=49|PinLength=7|Location.X=1050|Location.Y=673|Name=1|Designator=1|PinPropagationDelay=0.000000E+000
|RECORD=2|OwnerIndex=2813|OwnerPartId=1|Electrical=4|PinConglomerate=51|PinLength=6|Location.X=1050|Location.Y=666|Name=2|Designator=2|PinPropagationDelay=0.000000E+000
|RECORD=13|OwnerIndex=2813|IsNotAccesible=T|IndexInSheet=2|OwnerPartId=1|Location.X=1060|Location.Y=673|Corner.X=1040|Corner.Y=673|LineWidth=1|Color=16711680
|RECORD=13|OwnerIndex=2813|IsNotAccesible=T|IndexInSheet=3|OwnerPartId=1|Location.X=1060|Location.Y=667|Corner.X=1040|Corner.Y=667|LineWidth=1|Color=16711680
|RECORD=13|OwnerIndex=2813|IsNotAccesible=T|IndexInSheet=4|OwnerPartId=1|Location.X=1050|Location.Y=673|Corner.X=1050|Corner.Y=676|LineWidth=1|Color=16711680
|RECORD=13|OwnerIndex=2813|IsNotAccesible=T|IndexInSheet=5|OwnerPartId=1|Location.X=1050|Location.Y=666|Corner.X=1050|Corner.Y=665|LineWidth=1|Color=16711680
|RECORD=41|OwnerIndex=2813|IndexInSheet=6|OwnerPartId=-1|Location.X=1039|Location.Y=682|Color=8388608|FontID=1|IsHidden=T|Text=No SVHC|Name=REACH SVHC
|RECORD=41|OwnerIndex=2813|IndexInSheet=7|OwnerPartId=-1|Location.X=1039|Location.Y=682|Color=8388608|FontID=1|IsHidden=T|Text=C|Name=Series
|RECORD=41|OwnerIndex=2813|IndexInSheet=8|OwnerPartId=-1|Location.X=1039|Location.Y=682|Color=8388608|FontID=1|IsHidden=T|Text=SMD/SMT|Name=Termination
|RECORD=41|OwnerIndex=2813|IndexInSheet=9|OwnerPartId=-1|Location.X=1039|Location.Y=682|Color=8388608|FontID=1|IsHidden=T|Text=0402|Name=Case Code (Imperial)
|RECORD=41|OwnerIndex=2813|IndexInSheet=10|OwnerPartId=-1|Location.X=1039|Location.Y=682|Color=8388608|FontID=1|IsHidden=T|Text=0.5mm|Name=Depth
|RECORD=41|OwnerIndex=2813|IndexInSheet=11|OwnerPartId=-1|Location.X=1039|Location.Y=682|Color=8388608|FontID=1|IsHidden=T|Text=Surface Mount|Name=Mount
|RECORD=41|OwnerIndex=2813|IndexInSheet=12|OwnerPartId=-1|Location.X=1039|Location.Y=682|Color=8388608|FontID=1|IsHidden=T|Text=0.02inch|Name=Width
|RECORD=41|OwnerIndex=2813|IndexInSheet=13|OwnerPartId=-1|Location.X=1039|Location.Y=682|Color=8388608|FontID=1|IsHidden=T|Text=1|Name=Package Quantity
|RECORD=41|OwnerIndex=2813|IndexInSheet=14|OwnerPartId=-1|Location.X=1039|Location.Y=682|Color=8388608|FontID=1|IsHidden=T|Text=Ceramic|Name=Dielectric Material
|RECORD=41|OwnerIndex=2813|IndexInSheet=15|OwnerPartId=-1|Location.X=1039|Location.Y=682|Color=8388608|FontID=1|IsHidden=T|Text=1mm|Name=Length
|RECORD=41|OwnerIndex=2813|IndexInSheet=16|OwnerPartId=-1|Location.X=1039|Location.Y=682|Color=8388608|FontID=1|IsHidden=T|Text=Tape and Reel|Name=Packaging
|RECORD=41|OwnerIndex=2813|IndexInSheet=17|OwnerPartId=-1|Location.X=1039|Location.Y=682|Color=8388608|FontID=1|IsHidden=T|Text=1005|Name=Case Code (Metric)
|RECORD=41|OwnerIndex=2813|IndexInSheet=18|OwnerPartId=-1|Location.X=1039|Location.Y=682|Color=8388608|FontID=1|IsHidden=T|Text=Yes|Name=RoHS Compliant
|RECORD=41|OwnerIndex=2813|IndexInSheet=19|OwnerPartId=-1|Location.X=1039|Location.Y=682|Color=8388608|FontID=1|IsHidden=T|Text=X5R|Name=Dielectric
|RECORD=41|OwnerIndex=2813|IndexInSheet=20|OwnerPartId=-1|Location.X=1039|Location.Y=682|Color=8388608|FontID=1|IsHidden=T|Text=85°C|Name=Max Operating Temperature
|RECORD=41|OwnerIndex=2813|IndexInSheet=21|OwnerPartId=-1|Location.X=1039|Location.Y=682|Color=8388608|FontID=1|IsHidden=T|Text=Lead Free|Name=Lead Free
|RECORD=41|OwnerIndex=2813|IndexInSheet=22|OwnerPartId=-1|Location.X=1039|Location.Y=682|Color=8388608|FontID=1|IsHidden=T|Text=2.3E-05oz|Name=Weight
|RECORD=41|OwnerIndex=2813|IndexInSheet=23|OwnerPartId=-1|Location.X=1039|Location.Y=682|Color=8388608|FontID=1|IsHidden=T|Text=0.022inch|Name=Thickness
|RECORD=41|OwnerIndex=2813|IndexInSheet=24|OwnerPartId=-1|Location.X=1039|Location.Y=682|Color=8388608|FontID=1|IsHidden=T|Text=2.2uF|Name=Capacitance
|RECORD=41|OwnerIndex=2813|IndexInSheet=25|OwnerPartId=-1|Location.X=1039|Location.Y=682|Color=8388608|FontID=1|IsHidden=T|Text=16V|Name=Voltage Rating (DC)
|RECORD=41|OwnerIndex=2813|IndexInSheet=26|OwnerPartId=-1|Location.X=1039|Location.Y=682|Color=8388608|FontID=1|IsHidden=T|Text=10%|Name=Tolerance
|RECORD=41|OwnerIndex=2813|IndexInSheet=27|OwnerPartId=-1|Location.X=1039|Location.Y=682|Color=8388608|FontID=1|IsHidden=T|Text=16V|Name=Voltage Rating
|RECORD=41|OwnerIndex=2813|IndexInSheet=28|OwnerPartId=-1|Location.X=1039|Location.Y=682|Color=8388608|FontID=1|IsHidden=T|Text=Ceramic|Name=Resistor Type
|RECORD=41|OwnerIndex=2813|IndexInSheet=29|OwnerPartId=-1|Location.X=1039|Location.Y=682|Color=8388608|FontID=1|IsHidden=T|Text=0.5mm|Name=Height
|RECORD=41|OwnerIndex=2813|IndexInSheet=30|OwnerPartId=-1|Location.X=1039|Location.Y=682|Color=8388608|FontID=1|IsHidden=T|Text=0402|Name=Case/Package
|RECORD=41|OwnerIndex=2813|IndexInSheet=31|OwnerPartId=-1|Location.X=1039|Location.Y=682|Color=8388608|FontID=1|IsHidden=T|Text=-55°C|Name=Min Operating Temperature
|RECORD=34|OwnerIndex=2813|IndexInSheet=-1|OwnerPartId=-1|Location.X=1040|Location.Y=660|Orientation=1|Color=8388608|FontID=2|Text=C7|Name=Designator|ReadOnlyState=1
|RECORD=41|OwnerIndex=2813|IndexInSheet=-1|OwnerPartId=1|Location.X=1070|Location.Y=635|Orientation=1|Color=8388608|FontID=2|Text=2.2uF_16V_0402|Name=Comment
|RECORD=44|OwnerIndex=2813
|RECORD=45|OwnerIndex=2850|IndexInSheet=-1|UseComponentLibrary=T|ModelName=FP-C1005-050-0_05-IPC_A|ModelType=PCBLIB|DatafileCount=1|ModelDatafileEntity0=FP-C1005-050-0_05-IPC_A|ModelDatafileKind0=PCBLib|IsCurrent=T|DatalinksLocked=T|DatabaseDatalinksLocked=T
|RECORD=46|OwnerIndex=2851
|RECORD=48|OwnerIndex=2851
|RECORD=45|OwnerIndex=2850|IndexInSheet=-1|UseComponentLibrary=T|ModelName=FP-C1005-050-0_05-MFG|ModelType=PCBLIB|DatafileCount=1|ModelDatafileEntity0=FP-C1005-050-0_05-MFG|ModelDatafileKind0=PCBLib|DatalinksLocked=T|DatabaseDatalinksLocked=T
|RECORD=46|OwnerIndex=2854
|RECORD=48|OwnerIndex=2854
|RECORD=45|OwnerIndex=2850|IndexInSheet=-1|UseComponentLibrary=T|ModelName=FP-C1005-050-0_05-IPC_C|ModelType=PCBLIB|DatafileCount=1|ModelDatafileEntity0=FP-C1005-050-0_05-IPC_C|ModelDatafileKind0=PCBLib|DatalinksLocked=T|DatabaseDatalinksLocked=T
|RECORD=46|OwnerIndex=2857
|RECORD=48|OwnerIndex=2857
|RECORD=45|OwnerIndex=2850|IndexInSheet=-1|UseComponentLibrary=T|ModelName=FP-C1005-050-0_05-IPC_B|ModelType=PCBLIB|DatafileCount=1|ModelDatafileEntity0=FP-C1005-050-0_05-IPC_B|ModelDatafileKind0=PCBLib|DatalinksLocked=T|DatabaseDatalinksLocked=T
|RECORD=46|OwnerIndex=2860
|RECORD=48|OwnerIndex=2860
|RECORD=17|IndexInSheet=221|OwnerPartId=-1|Style=4|ShowNetName=T|Location.X=1010|Location.Y=630|Orientation=3|Color=128|FontID=1|Text=GND
|RECORD=27|IndexInSheet=222|OwnerPartId=-1|LineWidth=1|Color=8388608|LocationCount=2|X1=190|Y1=880|X2=190|Y2=850
|RECORD=27|IndexInSheet=223|OwnerPartId=-1|LineWidth=1|Color=8388608|LocationCount=2|X1=240|Y1=840|X2=240|Y2=850
|RECORD=27|IndexInSheet=224|OwnerPartId=-1|LineWidth=1|Color=8388608|LocationCount=2|X1=1640|Y1=810|X2=1560|Y2=810
|RECORD=27|IndexInSheet=225|OwnerPartId=-1|LineWidth=1|Color=8388608|LocationCount=2|X1=1560|Y1=800|X2=1640|Y2=800
|RECORD=27|IndexInSheet=226|OwnerPartId=-1|LineWidth=1|Color=8388608|LocationCount=3|X1=1560|Y1=770|X2=1600|Y2=770|X3=1600|Y3=710
|RECORD=27|IndexInSheet=227|OwnerPartId=-1|LineWidth=1|Color=8388608|LocationCount=3|X1=1450|Y1=810|X2=1410|Y2=810|X3=1410|Y3=860
|RECORD=27|IndexInSheet=228|OwnerPartId=-1|LineWidth=1|Color=8388608|LocationCount=2|X1=1410|Y1=810|X2=1410|Y2=750
|RECORD=27|IndexInSheet=229|OwnerPartId=-1|LineWidth=1|Color=8388608|LocationCount=2|X1=1360|Y1=860|X2=1360|Y2=840
|RECORD=27|IndexInSheet=230|OwnerPartId=-1|LineWidth=1|Color=8388608|LocationCount=3|X1=1450|Y1=770|X2=1360|Y2=770|X3=1360|Y3=800
|RECORD=27|IndexInSheet=231|OwnerPartId=-1|LineWidth=1|Color=8388608|LocationCount=2|X1=1410|Y1=720|X2=1410|Y2=710
|RECORD=27|IndexInSheet=232|OwnerPartId=-1|LineWidth=1|Color=8388608|LocationCount=2|X1=1360|Y1=770|X2=1340|Y2=770
|RECORD=27|IndexInSheet=233|OwnerPartId=-1|LineWidth=1|Color=8388608|LocationCount=2|X1=680|Y1=190|X2=680|Y2=170
|RECORD=27|IndexInSheet=234|OwnerPartId=-1|LineWidth=1|Color=8388608|LocationCount=2|X1=630|Y1=190|X2=630|Y2=170
|RECORD=27|IndexInSheet=235|OwnerPartId=-1|LineWidth=1|Color=8388608|LocationCount=3|X1=710|Y1=310|X2=680|Y2=310|X3=680|Y3=220
|RECORD=27|IndexInSheet=236|OwnerPartId=-1|LineWidth=1|Color=8388608|LocationCount=3|X1=710|Y1=320|X2=630|Y2=320|X3=630|Y3=220
|RECORD=27|IndexInSheet=237|OwnerPartId=-1|LineWidth=1|Color=8388608|LocationCount=2|X1=680|Y1=310|X2=680|Y2=370
|RECORD=27|IndexInSheet=238|OwnerPartId=-1|LineWidth=1|Color=8388608|LocationCount=2|X1=630|Y1=320|X2=630|Y2=370
|RECORD=27|IndexInSheet=239|OwnerPartId=-1|LineWidth=1|Color=8388608|LocationCount=2|X1=850|Y1=310|X2=930|Y2=310
|RECORD=27|IndexInSheet=240|OwnerPartId=-1|LineWidth=1|Color=8388608|LocationCount=2|X1=850|Y1=320|X2=930|Y2=320
|RECORD=27|IndexInSheet=241|OwnerPartId=-1|LineWidth=1|Color=8388608|LocationCount=3|X1=850|Y1=290|X2=890|Y2=290|X3=890|Y3=370
|RECORD=27|IndexInSheet=242|OwnerPartId=-1|LineWidth=1|Color=8388608|LocationCount=3|X1=850|Y1=300|X2=930|Y2=300|X3=930|Y3=170
|RECORD=27|IndexInSheet=243|OwnerPartId=-1|LineWidth=1|Color=8388608|LocationCount=2|X1=850|Y1=260|X2=890|Y2=260
|RECORD=27|IndexInSheet=244|OwnerPartId=-1|LineWidth=1|Color=8388608|LocationCount=2|X1=80|Y1=670|X2=80|Y2=640
|RECORD=27|IndexInSheet=245|OwnerPartId=-1|LineWidth=1|Color=8388608|LocationCount=2|X1=130|Y1=630|X2=130|Y2=640
|RECORD=27|IndexInSheet=246|OwnerPartId=-1|LineWidth=1|Color=8388608|LocationCount=2|X1=180|Y1=650|X2=180|Y2=630
|RECORD=27|IndexInSheet=247|OwnerPartId=-1|LineWidth=1|Color=8388608|LocationCount=2|X1=230|Y1=630|X2=230|Y2=650
|RECORD=27|IndexInSheet=248|OwnerPartId=-1|LineWidth=1|Color=8388608|LocationCount=4|X1=130|Y1=600|X2=130|Y2=590|X3=80|Y3=590|X4=80|Y4=610
|RECORD=27|IndexInSheet=249|OwnerPartId=-1|LineWidth=1|Color=8388608|LocationCount=4|X1=230|Y1=600|X2=230|Y2=590|X3=180|Y3=590|X4=180|Y4=610
|RECORD=27|IndexInSheet=250|OwnerPartId=-1|LineWidth=1|Color=8388608|LocationCount=4|X1=240|Y1=810|X2=240|Y2=800|X3=190|Y3=800|X4=190|Y4=820
|RECORD=27|IndexInSheet=251|OwnerPartId=-1|LineWidth=1|Color=8388608|LocationCount=4|X1=340|Y1=810|X2=340|Y2=800|X3=290|Y3=800|X4=290|Y4=820
|RECORD=27|IndexInSheet=252|OwnerPartId=-1|LineWidth=1|Color=8388608|LocationCount=3|X1=180|Y1=110|X2=140|Y2=110|X3=140|Y3=70
|RECORD=27|IndexInSheet=253|OwnerPartId=-1|LineWidth=1|Color=8388608|LocationCount=3|X1=260|Y1=110|X2=300|Y2=110|X3=300|Y3=70
|RECORD=27|IndexInSheet=254|OwnerPartId=-1|LineWidth=1|Color=8388608|LocationCount=3|X1=180|Y1=100|X2=160|Y2=100|X3=160|Y3=190
|RECORD=27|IndexInSheet=255|OwnerPartId=-1|LineWidth=1|Color=8388608|LocationCount=3|X1=260|Y1=100|X2=280|Y2=100|X3=280|Y3=190
|RECORD=27|IndexInSheet=256|OwnerPartId=-1|LineWidth=1|Color=8388608|LocationCount=2|X1=260|Y1=150|X2=330|Y2=150
|RECORD=27|IndexInSheet=257|OwnerPartId=-1|LineWidth=1|Color=8388608|LocationCount=2|X1=260|Y1=140|X2=330|Y2=140
|RECORD=27|IndexInSheet=258|OwnerPartId=-1|LineWidth=1|Color=8388608|LocationCount=2|X1=260|Y1=130|X2=330|Y2=130
|RECORD=27|IndexInSheet=259|OwnerPartId=-1|LineWidth=1|Color=8388608|LocationCount=2|X1=260|Y1=120|X2=330|Y2=120
|RECORD=27|IndexInSheet=260|OwnerPartId=-1|LineWidth=1|Color=8388608|LocationCount=2|X1=110|Y1=150|X2=180|Y2=150
|RECORD=27|IndexInSheet=261|OwnerPartId=-1|LineWidth=1|Color=8388608|LocationCount=2|X1=110|Y1=140|X2=180|Y2=140
|RECORD=27|IndexInSheet=262|OwnerPartId=-1|LineWidth=1|Color=8388608|LocationCount=2|X1=110|Y1=130|X2=180|Y2=130
|RECORD=27|IndexInSheet=263|OwnerPartId=-1|LineWidth=1|Color=8388608|LocationCount=2|X1=110|Y1=120|X2=180|Y2=120
|RECORD=27|IndexInSheet=264|OwnerPartId=-1|LineWidth=1|Color=8388608|LocationCount=3|X1=690|Y1=860|X2=710|Y2=860|X3=710|Y3=790
|RECORD=27|IndexInSheet=265|OwnerPartId=-1|LineWidth=1|Color=8388608|LocationCount=3|X1=340|Y1=860|X2=290|Y2=860|X3=290|Y3=840
|RECORD=27|IndexInSheet=266|OwnerPartId=-1|LineWidth=1|Color=8388608|LocationCount=2|X1=290|Y1=860|X2=290|Y2=880
|RECORD=27|IndexInSheet=267|OwnerPartId=-1|LineWidth=1|Color=8388608|LocationCount=3|X1=550|Y1=1030|X2=470|Y2=1030|X3=470|Y3=860
|RECORD=27|IndexInSheet=268|OwnerPartId=-1|LineWidth=1|Color=8388608|LocationCount=3|X1=550|Y1=1020|X2=480|Y2=1020|X3=480|Y3=850
|RECORD=27|IndexInSheet=269|OwnerPartId=-1|LineWidth=1|Color=8388608|LocationCount=3|X1=550|Y1=1010|X2=490|Y2=1010|X3=490|Y3=840
|RECORD=27|IndexInSheet=270|OwnerPartId=-1|LineWidth=1|Color=8388608|LocationCount=3|X1=550|Y1=1000|X2=500|Y2=1000|X3=500|Y3=830
|RECORD=27|IndexInSheet=271|OwnerPartId=-1|LineWidth=1|Color=8388608|LocationCount=3|X1=660|Y1=1030|X2=770|Y2=1030|X3=770|Y3=830
|RECORD=27|IndexInSheet=272|OwnerPartId=-1|LineWidth=1|Color=8388608|LocationCount=3|X1=660|Y1=1020|X2=760|Y2=1020|X3=760|Y3=840
|RECORD=27|IndexInSheet=273|OwnerPartId=-1|LineWidth=1|Color=8388608|LocationCount=3|X1=660|Y1=1010|X2=750|Y2=1010|X3=750|Y3=850
|RECORD=27|IndexInSheet=274|OwnerPartId=-1|LineWidth=1|Color=8388608|LocationCount=3|X1=660|Y1=1000|X2=710|Y2=1000|X3=710|Y3=860
|RECORD=27|IndexInSheet=275|OwnerPartId=-1|LineWidth=1|Color=8388608|LocationCount=3|X1=440|Y1=520|X2=410|Y2=520|X3=410|Y3=650
|RECORD=27|IndexInSheet=276|OwnerPartId=-1|LineWidth=1|Color=8388608|LocationCount=3|X1=440|Y1=510|X2=400|Y2=510|X3=400|Y3=640
|RECORD=27|IndexInSheet=277|OwnerPartId=-1|LineWidth=1|Color=8388608|LocationCount=3|X1=440|Y1=500|X2=390|Y2=500|X3=390|Y3=630
|RECORD=27|IndexInSheet=278|OwnerPartId=-1|LineWidth=1|Color=8388608|LocationCount=3|X1=440|Y1=490|X2=380|Y2=490|X3=380|Y3=620
|RECORD=27|IndexInSheet=279|OwnerPartId=-1|LineWidth=1|Color=8388608|LocationCount=3|X1=550|Y1=490|X2=590|Y2=490|X3=590|Y3=650
|RECORD=27|IndexInSheet=280|OwnerPartId=-1|LineWidth=1|Color=8388608|LocationCount=3|X1=550|Y1=520|X2=660|Y2=520|X3=660|Y3=620
|RECORD=27|IndexInSheet=281|OwnerPartId=-1|LineWidth=1|Color=8388608|LocationCount=3|X1=550|Y1=510|X2=650|Y2=510|X3=650|Y3=630
|RECORD=27|IndexInSheet=282|OwnerPartId=-1|LineWidth=1|Color=8388608|LocationCount=3|X1=550|Y1=500|X2=640|Y2=500|X3=640|Y3=640
|RECORD=27|IndexInSheet=283|OwnerPartId=-1|LineWidth=1|Color=8388608|LocationCount=4|X1=450|Y1=150|X2=480|Y2=150|X3=530|Y3=150|X4=530|Y4=180
|RECORD=27|IndexInSheet=284|OwnerPartId=-1|LineWidth=1|Color=8388608|LocationCount=3|X1=450|Y1=140|X2=500|Y2=140|X3=500|Y3=70
|RECORD=27|IndexInSheet=285|OwnerPartId=-1|LineWidth=1|Color=8388608|LocationCount=2|X1=450|Y1=130|X2=520|Y2=130
|RECORD=27|IndexInSheet=286|OwnerPartId=-1|LineWidth=1|Color=8388608|LocationCount=2|X1=450|Y1=120|X2=520|Y2=120
|RECORD=27|IndexInSheet=287|OwnerPartId=-1|LineWidth=1|Color=8388608|LocationCount=3|X1=590|Y1=100|X2=660|Y2=100|X3=680|Y3=100
|RECORD=27|IndexInSheet=288|OwnerPartId=-1|LineWidth=1|Color=8388608|LocationCount=4|X1=450|Y1=110|X2=520|Y2=110|X3=520|Y3=100|X4=550|Y4=100
|RECORD=27|IndexInSheet=289|OwnerPartId=-1|LineWidth=1|Color=8388608|LocationCount=3|X1=420|Y1=620|X2=380|Y2=620|X3=330|Y3=620
|RECORD=27|IndexInSheet=290|OwnerPartId=-1|LineWidth=1|Color=8388608|LocationCount=3|X1=420|Y1=630|X2=390|Y2=630|X3=330|Y3=630
|RECORD=27|IndexInSheet=291|OwnerPartId=-1|LineWidth=1|Color=8388608|LocationCount=5|X1=80|Y1=630|X2=80|Y2=640|X3=130|Y3=640|X4=400|Y4=640|X5=420|Y5=640
|RECORD=27|IndexInSheet=292|OwnerPartId=-1|LineWidth=1|Color=8388608|LocationCount=5|X1=180|Y1=670|X2=180|Y2=650|X3=230|Y3=650|X4=410|Y4=650|X5=420|Y5=650
|RECORD=27|IndexInSheet=293|OwnerPartId=-1|LineWidth=1|Color=8388608|LocationCount=3|X1=580|Y1=620|X2=660|Y2=620|X3=670|Y3=620
|RECORD=27|IndexInSheet=294|OwnerPartId=-1|LineWidth=1|Color=8388608|LocationCount=3|X1=670|Y1=630|X2=650|Y2=630|X3=580|Y3=630
|RECORD=27|IndexInSheet=295|OwnerPartId=-1|LineWidth=1|Color=8388608|LocationCount=3|X1=670|Y1=640|X2=640|Y2=640|X3=580|Y3=640
|RECORD=27|IndexInSheet=296|OwnerPartId=-1|LineWidth=1|Color=8388608|LocationCount=4|X1=580|Y1=650|X2=590|Y2=650|X3=600|Y3=650|X4=600|Y4=580
|RECORD=27|IndexInSheet=297|OwnerPartId=-1|LineWidth=1|Color=8388608|LocationCount=3|X1=530|Y1=830|X2=500|Y2=830|X3=440|Y3=830
|RECORD=27|IndexInSheet=298|OwnerPartId=-1|LineWidth=1|Color=8388608|LocationCount=4|X1=530|Y1=860|X2=470|Y2=860|X3=340|Y3=860|X4=340|Y4=840
|RECORD=27|IndexInSheet=299|OwnerPartId=-1|LineWidth=1|Color=8388608|LocationCount=5|X1=190|Y1=840|X2=190|Y2=850|X3=240|Y3=850|X4=480|Y4=850|X5=530|Y5=850
|RECORD=27|IndexInSheet=300|OwnerPartId=-1|LineWidth=1|Color=8388608|LocationCount=3|X1=530|Y1=840|X2=490|Y2=840|X3=440|Y3=840
|RECORD=27|IndexInSheet=301|OwnerPartId=-1|LineWidth=1|Color=8388608|LocationCount=3|X1=780|Y1=830|X2=770|Y2=830|X3=690|Y3=830
|RECORD=27|IndexInSheet=302|OwnerPartId=-1|LineWidth=1|Color=8388608|LocationCount=3|X1=780|Y1=840|X2=760|Y2=840|X3=690|Y3=840
|RECORD=27|IndexInSheet=303|OwnerPartId=-1|LineWidth=1|Color=8388608|LocationCount=3|X1=780|Y1=850|X2=750|Y2=850|X3=690|Y3=850
|RECORD=27|IndexInSheet=304|OwnerPartId=-1|LineWidth=1|Color=8388608|LocationCount=2|X1=100|Y1=490|X2=100|Y2=460
|RECORD=27|IndexInSheet=305|OwnerPartId=-1|LineWidth=1|Color=8388608|LocationCount=2|X1=150|Y1=450|X2=150|Y2=460
|RECORD=27|IndexInSheet=306|OwnerPartId=-1|LineWidth=1|Color=8388608|LocationCount=2|X1=200|Y1=470|X2=200|Y2=450
|RECORD=27|IndexInSheet=307|OwnerPartId=-1|LineWidth=1|Color=8388608|LocationCount=2|X1=250|Y1=450|X2=250|Y2=470
|RECORD=27|IndexInSheet=308|OwnerPartId=-1|LineWidth=1|Color=8388608|LocationCount=4|X1=150|Y1=420|X2=150|Y2=410|X3=100|Y3=410|X4=100|Y4=430
|RECORD=27|IndexInSheet=309|OwnerPartId=-1|LineWidth=1|Color=8388608|LocationCount=4|X1=250|Y1=420|X2=250|Y2=410|X3=200|Y3=410|X4=200|Y4=430
|RECORD=27|IndexInSheet=310|OwnerPartId=-1|LineWidth=1|Color=8388608|LocationCount=4|X1=100|Y1=450|X2=100|Y2=460|X3=150|Y3=460|X4=440|Y4=460
|RECORD=27|IndexInSheet=311|OwnerPartId=-1|LineWidth=1|Color=8388608|LocationCount=4|X1=200|Y1=490|X2=200|Y2=470|X3=250|Y3=470|X4=440|Y4=470
|RECORD=27|IndexInSheet=312|OwnerPartId=-1|LineWidth=1|Color=8388608|LocationCount=3|X1=550|Y1=440|X2=590|Y2=440|X3=590|Y3=410
|RECORD=27|IndexInSheet=313|OwnerPartId=-1|LineWidth=1|Color=8388608|LocationCount=3|X1=660|Y1=950|X2=680|Y2=950|X3=680|Y3=930
|RECORD=27|IndexInSheet=314|OwnerPartId=-1|LineWidth=1|Color=8388608|LocationCount=2|X1=120|Y1=1000|X2=120|Y2=970
|RECORD=27|IndexInSheet=315|OwnerPartId=-1|LineWidth=1|Color=8388608|LocationCount=2|X1=170|Y1=960|X2=170|Y2=970
|RECORD=27|IndexInSheet=316|OwnerPartId=-1|LineWidth=1|Color=8388608|LocationCount=4|X1=170|Y1=930|X2=170|Y2=920|X3=120|Y3=920|X4=120|Y4=940
|RECORD=27|IndexInSheet=317|OwnerPartId=-1|LineWidth=1|Color=8388608|LocationCount=4|X1=270|Y1=930|X2=270|Y2=920|X3=220|Y3=920|X4=220|Y4=940
|RECORD=27|IndexInSheet=318|OwnerPartId=-1|LineWidth=1|Color=8388608|LocationCount=3|X1=270|Y1=980|X2=220|Y2=980|X3=220|Y3=960
|RECORD=27|IndexInSheet=319|OwnerPartId=-1|LineWidth=1|Color=8388608|LocationCount=2|X1=220|Y1=980|X2=220|Y2=1000
|RECORD=27|IndexInSheet=320|OwnerPartId=-1|LineWidth=1|Color=8388608|LocationCount=3|X1=550|Y1=980|X2=270|Y2=980|X3=270|Y3=960
|RECORD=27|IndexInSheet=321|OwnerPartId=-1|LineWidth=1|Color=8388608|LocationCount=4|X1=120|Y1=960|X2=120|Y2=970|X3=170|Y3=970|X4=550|Y4=970
|RECORD=27|IndexInSheet=322|OwnerPartId=-1|LineWidth=1|Color=8388608|LocationCount=2|X1=410|Y1=960|X2=550|Y2=960
|RECORD=27|IndexInSheet=323|OwnerPartId=-1|LineWidth=1|Color=8388608|LocationCount=2|X1=550|Y1=950|X2=410|Y2=950
|RECORD=27|IndexInSheet=324|OwnerPartId=-1|LineWidth=1|Color=8388608|LocationCount=2|X1=660|Y1=980|X2=810|Y2=980
|RECORD=27|IndexInSheet=325|OwnerPartId=-1|LineWidth=1|Color=8388608|LocationCount=2|X1=810|Y1=970|X2=660|Y2=970
|RECORD=27|IndexInSheet=326|OwnerPartId=-1|LineWidth=1|Color=8388608|LocationCount=2|X1=660|Y1=960|X2=810|Y2=960
|RECORD=27|IndexInSheet=327|OwnerPartId=-1|LineWidth=1|Color=8388608|LocationCount=2|X1=370|Y1=450|X2=440|Y2=450
|RECORD=27|IndexInSheet=328|OwnerPartId=-1|LineWidth=1|Color=8388608|LocationCount=2|X1=440|Y1=440|X2=370|Y2=440
|RECORD=27|IndexInSheet=329|OwnerPartId=-1|LineWidth=1|Color=8388608|LocationCount=2|X1=550|Y1=470|X2=640|Y2=470
|RECORD=27|IndexInSheet=330|OwnerPartId=-1|LineWidth=1|Color=8388608|LocationCount=2|X1=640|Y1=460|X2=550|Y2=460
|RECORD=27|IndexInSheet=331|OwnerPartId=-1|LineWidth=1|Color=8388608|LocationCount=2|X1=550|Y1=450|X2=640|Y2=450
|RECORD=27|IndexInSheet=332|OwnerPartId=-1|LineWidth=1|Color=8388608|LocationCount=4|X1=1490|Y1=200|X2=1510|Y2=200|X3=1510|Y3=190|X4=1510|Y4=170
|RECORD=27|IndexInSheet=333|OwnerPartId=-1|LineWidth=1|Color=8388608|LocationCount=2|X1=1490|Y1=190|X2=1510|Y2=190
|RECORD=27|IndexInSheet=334|OwnerPartId=-1|LineWidth=1|Color=8388608|LocationCount=4|X1=1120|Y1=320|X2=1120|Y2=400|X3=1100|Y3=400|X4=1100|Y4=440
|RECORD=27|IndexInSheet=335|OwnerPartId=-1|LineWidth=1|Color=8388608|LocationCount=4|X1=1160|Y1=320|X2=1160|Y2=360|X3=1160|Y3=390|X4=1160|Y4=440
|RECORD=27|IndexInSheet=336|OwnerPartId=-1|LineWidth=1|Color=8388608|LocationCount=3|X1=1160|Y1=290|X2=1160|Y2=270|X3=1160|Y3=240
|RECORD=27|IndexInSheet=337|OwnerPartId=-1|LineWidth=1|Color=8388608|LocationCount=2|X1=1120|Y1=240|X2=1120|Y2=290
|RECORD=27|IndexInSheet=338|OwnerPartId=-1|LineWidth=1|Color=8388608|LocationCount=2|X1=1300|Y1=390|X2=1160|Y2=390
|RECORD=27|IndexInSheet=339|OwnerPartId=-1|LineWidth=1|Color=8388608|LocationCount=2|X1=1300|Y1=400|X2=1120|Y2=400
|RECORD=27|IndexInSheet=340|OwnerPartId=-1|LineWidth=1|Color=8388608|LocationCount=3|X1=1490|Y1=290|X2=1640|Y2=290|X3=1640|Y3=360
|RECORD=27|IndexInSheet=341|OwnerPartId=-1|LineWidth=1|Color=8388608|LocationCount=2|X1=1640|Y1=210|X2=1640|Y2=230
|RECORD=27|IndexInSheet=342|OwnerPartId=-1|LineWidth=1|Color=8388608|LocationCount=2|X1=1640|Y1=270|X2=1640|Y2=290
|RECORD=27|IndexInSheet=343|OwnerPartId=-1|LineWidth=1|Color=8388608|LocationCount=3|X1=1490|Y1=300|X2=1600|Y2=300|X3=1600|Y3=210
|RECORD=27|IndexInSheet=344|OwnerPartId=-1|LineWidth=1|Color=8388608|LocationCount=2|X1=1490|Y1=320|X2=1560|Y2=320
|RECORD=27|IndexInSheet=345|OwnerPartId=-1|LineWidth=1|Color=8388608|LocationCount=2|X1=1560|Y1=310|X2=1490|Y2=310
|RECORD=27|IndexInSheet=346|OwnerPartId=-1|LineWidth=1|Color=8388608|LocationCount=3|X1=1300|Y1=280|X2=1210|Y2=280|X3=1210|Y3=230
|RECORD=27|IndexInSheet=347|OwnerPartId=-1|LineWidth=1|Color=8388608|LocationCount=3|X1=1300|Y1=270|X2=1240|Y2=270|X3=1240|Y3=230
|RECORD=27|IndexInSheet=348|OwnerPartId=-1|LineWidth=1|Color=8388608|LocationCount=2|X1=1490|Y1=270|X2=1510|Y2=270
|RECORD=27|IndexInSheet=349|OwnerPartId=-1|LineWidth=1|Color=8388608|LocationCount=2|X1=1160|Y1=360|X2=1210|Y2=360
|RECORD=27|IndexInSheet=350|OwnerPartId=-1|LineWidth=1|Color=8388608|LocationCount=4|X1=1250|Y1=360|X2=1290|Y2=360|X3=1290|Y3=350|X4=1300|Y4=350
|RECORD=27|IndexInSheet=351|OwnerPartId=-1|LineWidth=1|Color=8388608|LocationCount=2|X1=1110|Y1=340|X2=1210|Y2=340
|RECORD=27|IndexInSheet=352|OwnerPartId=-1|LineWidth=1|Color=8388608|LocationCount=3|X1=1250|Y1=340|X2=1290|Y2=340|X3=1290|Y3=350
|RECORD=27|IndexInSheet=353|OwnerPartId=-1|LineWidth=1|Color=8388608|LocationCount=2|X1=1210|Y1=140|X2=1210|Y2=190
|RECORD=27|IndexInSheet=354|OwnerPartId=-1|LineWidth=1|Color=8388608|LocationCount=5|X1=1170|Y1=170|X2=1170|Y2=140|X3=1210|Y3=140|X4=1240|Y4=140|X5=1240|Y5=190
|RECORD=27|IndexInSheet=355|OwnerPartId=-1|LineWidth=1|Color=8388608|LocationCount=5|X1=1300|Y1=310|X2=1200|Y2=310|X3=1200|Y3=300|X4=1200|Y4=270|X5=1160|Y5=270
|RECORD=27|IndexInSheet=356|OwnerPartId=-1|LineWidth=1|Color=8388608|LocationCount=2|X1=1300|Y1=300|X2=1200|Y2=300
|RECORD=27|IndexInSheet=357|OwnerPartId=-1|LineWidth=1|Color=8388608|LocationCount=2|X1=1560|Y1=430|X2=1640|Y2=430
|RECORD=27|IndexInSheet=358|OwnerPartId=-1|LineWidth=1|Color=8388608|LocationCount=4|X1=1640|Y1=400|X2=1640|Y2=430|X3=1640|Y3=460|X4=1640|Y4=470
|RECORD=27|IndexInSheet=359|OwnerPartId=-1|LineWidth=1|Color=8388608|LocationCount=4|X1=1520|Y1=430|X2=1510|Y2=430|X3=1510|Y3=400|X4=1490|Y4=400
|RECORD=27|IndexInSheet=360|OwnerPartId=-1|LineWidth=1|Color=8388608|LocationCount=2|X1=1490|Y1=360|X2=1510|Y2=360
|RECORD=27|IndexInSheet=361|OwnerPartId=-1|LineWidth=1|Color=8388608|LocationCount=2|X1=1600|Y1=460|X2=1640|Y2=460
|RECORD=27|IndexInSheet=362|OwnerPartId=-1|LineWidth=1|Color=8388608|LocationCount=2|X1=1560|Y1=460|X2=1530|Y2=460
|RECORD=27|IndexInSheet=363|OwnerPartId=-1|LineWidth=1|Color=8388608|LocationCount=4|X1=1490|Y1=380|X2=1520|Y2=380|X3=1520|Y3=390|X4=1560|Y4=390
|RECORD=27|IndexInSheet=364|OwnerPartId=-1|LineWidth=1|Color=8388608|LocationCount=3|X1=1580|Y1=390|X2=1600|Y2=390|X3=1600|Y3=300
|RECORD=27|IndexInSheet=365|OwnerPartId=-1|LineWidth=1|Color=8388608|LocationCount=2|X1=1550|Y1=270|X2=1570|Y2=270
|RECORD=27|IndexInSheet=366|OwnerPartId=-1|LineWidth=1|Color=8388608|LocationCount=2|X1=1260|Y1=330|X2=1300|Y2=330
|RECORD=27|IndexInSheet=367|OwnerPartId=-1|LineWidth=1|Color=8388608|LocationCount=2|X1=1490|Y1=340|X2=1510|Y2=340
|RECORD=27|IndexInSheet=368|OwnerPartId=-1|LineWidth=1|Color=8388608|LocationCount=3|X1=460|Y1=300|X2=490|Y2=300|X3=490|Y3=320
|RECORD=27|IndexInSheet=369|OwnerPartId=-1|LineWidth=1|Color=8388608|LocationCount=2|X1=460|Y1=280|X2=530|Y2=280
|RECORD=27|IndexInSheet=370|OwnerPartId=-1|LineWidth=1|Color=8388608|LocationCount=2|X1=460|Y1=270|X2=530|Y2=270
|RECORD=27|IndexInSheet=371|OwnerPartId=-1|LineWidth=1|Color=8388608|LocationCount=3|X1=460|Y1=290|X2=490|Y2=290|X3=490|Y3=250
|RECORD=27|IndexInSheet=372|OwnerPartId=-1|LineWidth=1|Color=8388608|LocationCount=4|X1=850|Y1=270|X2=890|Y2=270|X3=890|Y3=260|X4=890|Y4=170
|RECORD=27|IndexInSheet=373|OwnerPartId=-1|LineWidth=1|Color=8388608|LocationCount=2|X1=1340|Y1=460|X2=1340|Y2=470
|RECORD=27|IndexInSheet=374|OwnerPartId=-1|LineWidth=1|Color=8388608|LocationCount=2|X1=1420|Y1=460|X2=1420|Y2=470
|RECORD=27|IndexInSheet=375|OwnerPartId=-1|LineWidth=1|Color=8388608|LocationCount=2|X1=1480|Y1=510|X2=1530|Y2=510
|RECORD=27|IndexInSheet=376|OwnerPartId=-1|LineWidth=1|Color=8388608|LocationCount=2|X1=1290|Y1=510|X2=1270|Y2=510
|RECORD=27|IndexInSheet=377|OwnerPartId=-1|LineWidth=1|Color=8388608|LocationCount=2|X1=1330|Y1=510|X2=1340|Y2=510
|RECORD=27|IndexInSheet=378|OwnerPartId=-1|LineWidth=1|Color=8388608|LocationCount=3|X1=1190|Y1=690|X2=1220|Y2=690|X3=1220|Y3=710
|RECORD=27|IndexInSheet=379|OwnerPartId=-1|LineWidth=1|Color=8388608|LocationCount=2|X1=1190|Y1=640|X2=1210|Y2=640
|RECORD=27|IndexInSheet=380|OwnerPartId=-1|LineWidth=1|Color=8388608|LocationCount=3|X1=1235|Y1=710|X2=1240|Y2=710|X3=1240|Y3=730
|RECORD=27|IndexInSheet=381|OwnerPartId=-1|LineWidth=1|Color=8388608|LocationCount=3|X1=1240|Y1=710|X2=1280|Y2=710|X3=1280|Y3=670
|RECORD=27|IndexInSheet=382|OwnerPartId=-1|LineWidth=1|Color=8388608|LocationCount=3|X1=1280|Y1=710|X2=1325|Y2=710|X3=1325|Y3=670
|RECORD=27|IndexInSheet=383|OwnerPartId=-1|LineWidth=1|Color=8388608|LocationCount=3|X1=1325|Y1=710|X2=1365|Y2=710|X3=1365|Y3=670
|RECORD=27|IndexInSheet=384|OwnerPartId=-1|LineWidth=1|Color=8388608|LocationCount=5|X1=1190|Y1=650|X2=1210|Y2=650|X3=1210|Y3=640|X4=1210|Y4=630|X5=1210|Y5=620
|RECORD=27|IndexInSheet=385|OwnerPartId=-1|LineWidth=1|Color=8388608|LocationCount=4|X1=1190|Y1=710|X2=1220|Y2=710|X3=1235|Y3=710|X4=1235|Y4=670
|RECORD=27|IndexInSheet=386|OwnerPartId=-1|LineWidth=1|Color=8388608|LocationCount=3|X1=1210|Y1=630|X2=1235|Y2=630|X3=1235|Y3=650
|RECORD=27|IndexInSheet=387|OwnerPartId=-1|LineWidth=1|Color=8388608|LocationCount=3|X1=1235|Y1=630|X2=1280|Y2=630|X3=1280|Y3=650
|RECORD=27|IndexInSheet=388|OwnerPartId=-1|LineWidth=1|Color=8388608|LocationCount=3|X1=1280|Y1=630|X2=1325|Y2=630|X3=1325|Y3=650
|RECORD=27|IndexInSheet=389|OwnerPartId=-1|LineWidth=1|Color=8388608|LocationCount=3|X1=1325|Y1=630|X2=1365|Y2=630|X3=1365|Y3=650
|RECORD=27|IndexInSheet=390|OwnerPartId=-1|LineWidth=1|Color=8388608|LocationCount=5|X1=1010|Y1=740|X2=1010|Y2=710|X3=1050|Y3=710|X4=1070|Y4=710|X5=1080|Y5=710
|RECORD=27|IndexInSheet=391|OwnerPartId=-1|LineWidth=1|Color=8388608|LocationCount=3|X1=1080|Y1=690|X2=1070|Y2=690|X3=1070|Y3=710
|RECORD=27|IndexInSheet=392|OwnerPartId=-1|LineWidth=1|Color=8388608|LocationCount=3|X1=1005|Y1=680|X2=1005|Y2=710|X3=1010|Y3=710
|RECORD=27|IndexInSheet=393|OwnerPartId=-1|LineWidth=1|Color=8388608|LocationCount=2|X1=1050|Y1=680|X2=1050|Y2=710
|RECORD=27|IndexInSheet=394|OwnerPartId=-1|LineWidth=1|Color=8388608|LocationCount=4|X1=1005|Y1=660|X2=1005|Y2=640|X3=1010|Y3=640|X4=1010|Y4=630
|RECORD=27|IndexInSheet=395|OwnerPartId=-1|LineWidth=1|Color=8388608|LocationCount=3|X1=1050|Y1=660|X2=1050|Y2=640|X3=1010|Y3=640
|RECORD=27|IndexInSheet=396|OwnerPartId=-1|LineWidth=1|Color=8388608|LocationCount=2|X1=1440|Y1=510|X2=1420|Y2=510
|RECORD=27|IndexInSheet=397|OwnerPartId=-1|LineWidth=1|Color=8388608|LocationCount=3|X1=1420|Y1=490|X2=1420|Y2=500|X3=1420|Y3=510
|RECORD=27|IndexInSheet=398|OwnerPartId=-1|LineWidth=1|Color=8388608|LocationCount=2|X1=1420|Y1=510|X2=1420|Y2=540
|RECORD=27|IndexInSheet=399|OwnerPartId=-1|LineWidth=1|Color=8388608|LocationCount=3|X1=1300|Y1=540|X2=1340|Y2=540|X3=1360|Y3=540
|RECORD=27|IndexInSheet=400|OwnerPartId=-1|LineWidth=1|Color=8388608|LocationCount=3|X1=1390|Y1=540|X2=1420|Y2=540|X3=1460|Y3=540
|RECORD=27|IndexInSheet=401|OwnerPartId=-1|LineWidth=1|Color=8388608|LocationCount=3|X1=1340|Y1=500|X2=1340|Y2=510|X3=1340|Y3=540
|RECORD=27|IndexInSheet=402|OwnerPartId=-1|LineWidth=1|Color=8388608|LocationCount=3|X1=600|Y1=80|X2=660|Y2=80|X3=660|Y3=100
|RECORD=27|IndexInSheet=403|OwnerPartId=-1|LineWidth=1|Color=8388608|LocationCount=3|X1=560|Y1=80|X2=480|Y2=80|X3=480|Y3=150
|RECORD=1|LibReference=CAP|PartCount=2|DisplayModeCount=2|IndexInSheet=404|OwnerPartId=-1|Location.X=1110|Location.Y=300|Orientation=1|CurrentPartId=1|SourceLibraryName=Altium Content Vault|TargetFileName=*|AreaColor=11599871|Color=128|PartIDLocked=F|DesignItemId=CMP-1034-02072-2|AllPinCount=2
|RECORD=2|OwnerIndex=3046|OwnerPartId=1|OwnerPartDisplayMode=1|FormalType=1|Electrical=4|PinConglomerate=35|PinLength=10|Location.X=1120|Location.Y=300|Name=1|Designator=1|PinPropagationDelay=0.000000E+000
|RECORD=2|OwnerIndex=3046|OwnerPartId=1|OwnerPartDisplayMode=1|FormalType=1|Electrical=4|PinConglomerate=33|PinLength=10|Location.X=1120|Location.Y=310|Name=2|Designator=2|PinPropagationDelay=0.000000E+000
|RECORD=13|OwnerIndex=3046|IsNotAccesible=T|IndexInSheet=2|OwnerPartId=1|OwnerPartDisplayMode=1|Location.X=1128|Location.Y=300|Corner.X=1112|Corner.Y=300|LineWidth=1|Color=16711680
|RECORD=13|OwnerIndex=3046|IsNotAccesible=T|IndexInSheet=3|OwnerPartId=1|OwnerPartDisplayMode=1|Location.X=1120|Location.Y=304|Corner.X=1120|Corner.Y=310|LineWidth=1|Color=16711680
|RECORD=12|OwnerIndex=3046|IsNotAccesible=T|IndexInSheet=4|OwnerPartId=1|OwnerPartDisplayMode=1|Location.X=1120|Location.Y=320|Radius=16|LineWidth=1|StartAngle=241.000|EndAngle=270.000|Color=16711680
|RECORD=12|OwnerIndex=3046|IsNotAccesible=T|IndexInSheet=5|OwnerPartId=1|OwnerPartDisplayMode=1|Location.X=1120|Location.Y=320|Radius=16|LineWidth=1|StartAngle=270.000|EndAngle=299.000|Color=16711680
|RECORD=2|OwnerIndex=3046|OwnerPartId=1|FormalType=1|Electrical=4|PinConglomerate=35|PinLength=10|Location.X=1120|Location.Y=300|Name=1|Designator=1|PinPropagationDelay=0.000000E+000
|RECORD=2|OwnerIndex=3046|OwnerPartId=1|FormalType=1|Electrical=4|PinConglomerate=33|PinLength=10|Location.X=1120|Location.Y=310|Name=2|Designator=2|PinPropagationDelay=0.000000E+000
|RECORD=13|OwnerIndex=3046|IsNotAccesible=T|IndexInSheet=8|OwnerPartId=1|Location.X=1112|Location.Y=307|Corner.X=1128|Corner.Y=307|LineWidth=1|Color=16711680
|RECORD=13|OwnerIndex=3046|IsNotAccesible=T|IndexInSheet=9|OwnerPartId=1|Location.X=1128|Location.Y=303|Corner.X=1112|Corner.Y=303|LineWidth=1|Color=16711680
|RECORD=6|OwnerIndex=3046|IsNotAccesible=T|IndexInSheet=10|OwnerPartId=1|LineWidth=1|Color=16711680|LocationCount=2|X1=1120|Y1=300|X2=1120|Y2=303
|RECORD=6|OwnerIndex=3046|IsNotAccesible=T|IndexInSheet=11|OwnerPartId=1|LineWidth=1|Color=16711680|LocationCount=2|X1=1120|Y1=310|X2=1120|Y2=307
|RECORD=41|OwnerIndex=3046|IndexInSheet=12|OwnerPartId=-1|Location.X=1111|Location.Y=322|Color=8388608|FontID=1|IsHidden=T|Text=04023D104KAT2A|Name=Part Number
|RECORD=41|OwnerIndex=3046|IndexInSheet=13|OwnerPartId=-1|Location.X=1111|Location.Y=322|Color=8388608|FontID=1|IsHidden=T|Text=AVX Interconnect / Elco|Name=Manufacturer
|RECORD=34|OwnerIndex=3046|IndexInSheet=-1|OwnerPartId=-1|Location.X=1110|Location.Y=290|Orientation=1|Color=8388608|FontID=2|Text=C67|Name=Designator|ReadOnlyState=1
|RECORD=41|OwnerIndex=3046|IndexInSheet=-1|OwnerPartId=-1|Location.X=1140|Location.Y=275|Orientation=1|Color=8388608|FontID=2|Text=0.1uF_25V_0402|Name=Comment
|RECORD=44|OwnerIndex=3046
|RECORD=45|OwnerIndex=3067|IndexInSheet=-1|Description=Chip Capacitor, 2-Leads, Body 1.00x0.50mm, IPC Medium Density|UseComponentLibrary=T|ModelName=CAPC1005X56X25NL10T15|ModelType=PCBLIB|DatafileCount=1|ModelDatafileEntity0=CAPC1005X56X25NL10T15|ModelDatafileKind0=PCBLib|IsCurrent=T|DatalinksLocked=T|DatabaseDatalinksLocked=T
|RECORD=46|OwnerIndex=3068
|RECORD=48|OwnerIndex=3068
|RECORD=41|OwnerIndex=3070|IndexInSheet=-1|OwnerPartId=-1|Color=8388608|FontID=1|IsHidden=T|Text=2D|Name=Available Preview Images
|RECORD=45|OwnerIndex=3067|IndexInSheet=-1|Description=Chip Capacitor, 2-Leads, Body 1.00x0.50mm, IPC High Density|UseComponentLibrary=T|ModelName=CAPC1005X56X25LL10T15|ModelType=PCBLIB|DatafileCount=1|ModelDatafileEntity0=CAPC1005X56X25LL10T15|ModelDatafileKind0=PCBLib|DatalinksLocked=T|DatabaseDatalinksLocked=T
|RECORD=46|OwnerIndex=3072
|RECORD=48|OwnerIndex=3072
|RECORD=41|OwnerIndex=3074|IndexInSheet=-1|OwnerPartId=-1|Color=8388608|FontID=1|IsHidden=T|Text=2D|Name=Available Preview Images
|RECORD=45|OwnerIndex=3067|IndexInSheet=-1|Description=Chip Capacitor, 2-Leads, Body 1.00x0.50mm, IPC Low Density|UseComponentLibrary=T|ModelName=CAPC1005X56X25ML10T15|ModelType=PCBLIB|DatafileCount=1|ModelDatafileEntity0=CAPC1005X56X25ML10T15|ModelDatafileKind0=PCBLib|DatalinksLocked=T|DatabaseDatalinksLocked=T
|RECORD=46|OwnerIndex=3076
|RECORD=48|OwnerIndex=3076
|RECORD=41|OwnerIndex=3078|IndexInSheet=-1|OwnerPartId=-1|Color=8388608|FontID=1|IsHidden=T|Text=2D|Name=Available Preview Images
|RECORD=1|LibReference=CAP|PartCount=2|DisplayModeCount=2|IndexInSheet=405|OwnerPartId=-1|Location.X=1150|Location.Y=300|Orientation=1|CurrentPartId=1|SourceLibraryName=Altium Content Vault|TargetFileName=*|AreaColor=11599871|Color=128|PartIDLocked=F|DesignItemId=CMP-1034-02072-2|AllPinCount=2
|RECORD=2|OwnerIndex=3080|OwnerPartId=1|OwnerPartDisplayMode=1|FormalType=1|Electrical=4|PinConglomerate=35|PinLength=10|Location.X=1160|Location.Y=300|Name=1|Designator=1|PinPropagationDelay=0.000000E+000
|RECORD=2|OwnerIndex=3080|OwnerPartId=1|OwnerPartDisplayMode=1|FormalType=1|Electrical=4|PinConglomerate=33|PinLength=10|Location.X=1160|Location.Y=310|Name=2|Designator=2|PinPropagationDelay=0.000000E+000
|RECORD=13|OwnerIndex=3080|IsNotAccesible=T|IndexInSheet=2|OwnerPartId=1|OwnerPartDisplayMode=1|Location.X=1168|Location.Y=300|Corner.X=1152|Corner.Y=300|LineWidth=1|Color=16711680
|RECORD=13|OwnerIndex=3080|IsNotAccesible=T|IndexInSheet=3|OwnerPartId=1|OwnerPartDisplayMode=1|Location.X=1160|Location.Y=304|Corner.X=1160|Corner.Y=310|LineWidth=1|Color=16711680
|RECORD=12|OwnerIndex=3080|IsNotAccesible=T|IndexInSheet=4|OwnerPartId=1|OwnerPartDisplayMode=1|Location.X=1160|Location.Y=320|Radius=16|LineWidth=1|StartAngle=241.000|EndAngle=270.000|Color=16711680
|RECORD=12|OwnerIndex=3080|IsNotAccesible=T|IndexInSheet=5|OwnerPartId=1|OwnerPartDisplayMode=1|Location.X=1160|Location.Y=320|Radius=16|LineWidth=1|StartAngle=270.000|EndAngle=299.000|Color=16711680
|RECORD=2|OwnerIndex=3080|OwnerPartId=1|FormalType=1|Electrical=4|PinConglomerate=35|PinLength=10|Location.X=1160|Location.Y=300|Name=1|Designator=1|PinPropagationDelay=0.000000E+000
|RECORD=2|OwnerIndex=3080|OwnerPartId=1|FormalType=1|Electrical=4|PinConglomerate=33|PinLength=10|Location.X=1160|Location.Y=310|Name=2|Designator=2|PinPropagationDelay=0.000000E+000
|RECORD=13|OwnerIndex=3080|IsNotAccesible=T|IndexInSheet=8|OwnerPartId=1|Location.X=1152|Location.Y=307|Corner.X=1168|Corner.Y=307|LineWidth=1|Color=16711680
|RECORD=13|OwnerIndex=3080|IsNotAccesible=T|IndexInSheet=9|OwnerPartId=1|Location.X=1168|Location.Y=303|Corner.X=1152|Corner.Y=303|LineWidth=1|Color=16711680
|RECORD=6|OwnerIndex=3080|IsNotAccesible=T|IndexInSheet=10|OwnerPartId=1|LineWidth=1|Color=16711680|LocationCount=2|X1=1160|Y1=300|X2=1160|Y2=303
|RECORD=6|OwnerIndex=3080|IsNotAccesible=T|IndexInSheet=11|OwnerPartId=1|LineWidth=1|Color=16711680|LocationCount=2|X1=1160|Y1=310|X2=1160|Y2=307
|RECORD=41|OwnerIndex=3080|IndexInSheet=12|OwnerPartId=-1|Location.X=1151|Location.Y=322|Color=8388608|FontID=1|IsHidden=T|Text=04023D104KAT2A|Name=Part Number
|RECORD=41|OwnerIndex=3080|IndexInSheet=13|OwnerPartId=-1|Location.X=1151|Location.Y=322|Color=8388608|FontID=1|IsHidden=T|Text=AVX Interconnect / Elco|Name=Manufacturer
|RECORD=34|OwnerIndex=3080|IndexInSheet=-1|OwnerPartId=-1|Location.X=1150|Location.Y=290|Orientation=1|Color=8388608|FontID=2|Text=C84|Name=Designator|ReadOnlyState=1
|RECORD=41|OwnerIndex=3080|IndexInSheet=-1|OwnerPartId=-1|Location.X=1180|Location.Y=275|Orientation=1|Color=8388608|FontID=2|Text=0.1uF_25V_0402|Name=Comment
|RECORD=44|OwnerIndex=3080
|RECORD=45|OwnerIndex=3101|IndexInSheet=-1|Description=Chip Capacitor, 2-Leads, Body 1.00x0.50mm, IPC Medium Density|UseComponentLibrary=T|ModelName=CAPC1005X56X25NL10T15|ModelType=PCBLIB|DatafileCount=1|ModelDatafileEntity0=CAPC1005X56X25NL10T15|ModelDatafileKind0=PCBLib|IsCurrent=T|DatalinksLocked=T|DatabaseDatalinksLocked=T
|RECORD=46|OwnerIndex=3102
|RECORD=48|OwnerIndex=3102
|RECORD=41|OwnerIndex=3104|IndexInSheet=-1|OwnerPartId=-1|Color=8388608|FontID=1|IsHidden=T|Text=2D|Name=Available Preview Images
|RECORD=45|OwnerIndex=3101|IndexInSheet=-1|Description=Chip Capacitor, 2-Leads, Body 1.00x0.50mm, IPC High Density|UseComponentLibrary=T|ModelName=CAPC1005X56X25LL10T15|ModelType=PCBLIB|DatafileCount=1|ModelDatafileEntity0=CAPC1005X56X25LL10T15|ModelDatafileKind0=PCBLib|DatalinksLocked=T|DatabaseDatalinksLocked=T
|RECORD=46|OwnerIndex=3106
|RECORD=48|OwnerIndex=3106
|RECORD=41|OwnerIndex=3108|IndexInSheet=-1|OwnerPartId=-1|Color=8388608|FontID=1|IsHidden=T|Text=2D|Name=Available Preview Images
|RECORD=45|OwnerIndex=3101|IndexInSheet=-1|Description=Chip Capacitor, 2-Leads, Body 1.00x0.50mm, IPC Low Density|UseComponentLibrary=T|ModelName=CAPC1005X56X25ML10T15|ModelType=PCBLIB|DatafileCount=1|ModelDatafileEntity0=CAPC1005X56X25ML10T15|ModelDatafileKind0=PCBLib|DatalinksLocked=T|DatabaseDatalinksLocked=T
|RECORD=46|OwnerIndex=3110
|RECORD=48|OwnerIndex=3110
|RECORD=41|OwnerIndex=3112|IndexInSheet=-1|OwnerPartId=-1|Color=8388608|FontID=1|IsHidden=T|Text=2D|Name=Available Preview Images
|RECORD=17|IndexInSheet=406|OwnerPartId=-1|ShowNetName=T|Location.X=80|Location.Y=670|Orientation=1|Color=128|FontID=1|Text=GNSS2_P3V3
|RECORD=17|IndexInSheet=407|OwnerPartId=-1|ShowNetName=T|Location.X=100|Location.Y=490|Orientation=1|Color=128|FontID=1|Text=GNSS2_P3V3
|RECORD=17|IndexInSheet=408|OwnerPartId=-1|ShowNetName=T|Location.X=180|Location.Y=670|Orientation=1|Color=128|FontID=1|Text=GNSS2_P5V0
|RECORD=17|IndexInSheet=409|OwnerPartId=-1|ShowNetName=T|Location.X=200|Location.Y=490|Orientation=1|Color=128|FontID=1|Text=GNSS2_P5V0
|RECORD=1|LibReference=RES|PartCount=2|DisplayModeCount=2|IndexInSheet=410|OwnerPartId=-1|Location.X=570|Location.Y=90|CurrentPartId=1|SourceLibraryName=Altium Content Vault|TargetFileName=*|AreaColor=11599871|Color=128|PartIDLocked=F|DesignItemId=CMP-2002-07353-1|AllPinCount=2
|RECORD=2|OwnerIndex=3118|OwnerPartId=1|OwnerPartDisplayMode=1|FormalType=1|Electrical=4|PinConglomerate=32|PinLength=10|Location.X=590|Location.Y=80|Name=2|Designator=2|PinPropagationDelay=0.000000E+000
|RECORD=2|OwnerIndex=3118|OwnerPartId=1|OwnerPartDisplayMode=1|FormalType=1|Electrical=4|PinConglomerate=34|PinLength=10|Location.X=570|Location.Y=80|Name=1|Designator=1|PinPropagationDelay=0.000000E+000
|RECORD=14|OwnerIndex=3118|IsNotAccesible=T|IndexInSheet=2|OwnerPartId=1|OwnerPartDisplayMode=1|Location.X=570|Location.Y=76|Corner.X=590|Corner.Y=84|LineWidth=1|Color=16711680|AreaColor=11599871
|RECORD=2|OwnerIndex=3118|OwnerPartId=1|FormalType=1|Electrical=4|PinConglomerate=32|PinLength=10|Location.X=590|Location.Y=80|Name=2|Designator=2|PinPropagationDelay=0.000000E+000
|RECORD=2|OwnerIndex=3118|OwnerPartId=1|FormalType=1|Electrical=4|PinConglomerate=34|PinLength=10|Location.X=570|Location.Y=80|Name=1|Designator=1|PinPropagationDelay=0.000000E+000
|RECORD=6|OwnerIndex=3118|IsNotAccesible=T|IndexInSheet=5|OwnerPartId=1|LineWidth=1|Color=16711680|LocationCount=10|X1=590|Y1=80|X2=586|Y2=80|X3=585|Y3=78|X4=583|Y4=82|X5=581|Y5=78|X6=579|Y6=82|X7=577|Y7=78|X8=575|Y8=82|X9=574|Y9=80|X10=570|Y10=80
|RECORD=41|OwnerIndex=3118|IndexInSheet=6|OwnerPartId=-1|Location.X=558|Location.Y=83|Color=8388608|FontID=1|IsHidden=T|Text=RC0402FR-0710KL|Name=Part Number
|RECORD=41|OwnerIndex=3118|IndexInSheet=7|OwnerPartId=-1|Location.X=558|Location.Y=83|Color=8388608|FontID=1|IsHidden=T|Text=Yageo / Phycomp|Name=Manufacturer
|RECORD=34|OwnerIndex=3118|IndexInSheet=-1|OwnerPartId=-1|Location.X=569|Location.Y=83|Color=8388608|FontID=1|Text=R186|Name=Designator|ReadOnlyState=1
|RECORD=41|OwnerIndex=3118|IndexInSheet=-1|OwnerPartId=-1|Location.X=569|Location.Y=67|Color=8388608|FontID=1|Text=10K_1%_0402|Name=Comment
|RECORD=44|OwnerIndex=3118
|RECORD=45|OwnerIndex=3133|IndexInSheet=-1|Description=Chip Resistor, 2-Leads, Body 1.00x0.50mm, IPC High Density|UseComponentLibrary=T|ModelName=RESC1005X40X25LL05T10|ModelType=PCBLIB|DatafileCount=1|ModelDatafileEntity0=RESC1005X40X25LL05T10|ModelDatafileKind0=PCBLib|IsCurrent=T|DatalinksLocked=T|DatabaseDatalinksLocked=T
|RECORD=46|OwnerIndex=3134
|RECORD=48|OwnerIndex=3134
|RECORD=41|OwnerIndex=3136|IndexInSheet=-1|OwnerPartId=-1|Color=8388608|FontID=1|IsHidden=T|Text=2D|Name=Available Preview Images
|RECORD=45|OwnerIndex=3133|IndexInSheet=-1|Description=Chip Resistor, 2-Leads, Body 1.00x0.50mm, IPC Low Density|UseComponentLibrary=T|ModelName=RESC1005X40X25ML05T10|ModelType=PCBLIB|DatafileCount=1|ModelDatafileEntity0=RESC1005X40X25ML05T10|ModelDatafileKind0=PCBLib|DatalinksLocked=T|DatabaseDatalinksLocked=T
|RECORD=46|OwnerIndex=3138
|RECORD=48|OwnerIndex=3138
|RECORD=41|OwnerIndex=3140|IndexInSheet=-1|OwnerPartId=-1|Color=8388608|FontID=1|IsHidden=T|Text=2D|Name=Available Preview Images
|RECORD=45|OwnerIndex=3133|IndexInSheet=-1|Description=Chip Resistor, 2-Leads, Body 1.00x0.50mm, IPC Medium Density|UseComponentLibrary=T|ModelName=RESC1005X40X25NL05T10|ModelType=PCBLIB|DatafileCount=1|ModelDatafileEntity0=RESC1005X40X25NL05T10|ModelDatafileKind0=PCBLib|DatalinksLocked=T|DatabaseDatalinksLocked=T
|RECORD=46|OwnerIndex=3142
|RECORD=48|OwnerIndex=3142
|RECORD=41|OwnerIndex=3144|IndexInSheet=-1|OwnerPartId=-1|Color=8388608|FontID=1|IsHidden=T|Text=2D|Name=Available Preview Images
|RECORD=29|IndexInSheet=-1|OwnerPartId=-1|Location.X=80|Location.Y=590|Color=128
|RECORD=29|IndexInSheet=-1|OwnerPartId=-1|Location.X=80|Location.Y=640|Color=128
|RECORD=29|IndexInSheet=-1|OwnerPartId=-1|Location.X=100|Location.Y=410|Color=128
|RECORD=29|IndexInSheet=-1|OwnerPartId=-1|Location.X=100|Location.Y=460|Color=128
|RECORD=29|IndexInSheet=-1|OwnerPartId=-1|Location.X=120|Location.Y=920|Color=128
|RECORD=29|IndexInSheet=-1|OwnerPartId=-1|Location.X=120|Location.Y=970|Color=128
|RECORD=29|IndexInSheet=-1|OwnerPartId=-1|Location.X=130|Location.Y=640|Color=128
|RECORD=29|IndexInSheet=-1|OwnerPartId=-1|Location.X=150|Location.Y=460|Color=128
|RECORD=29|IndexInSheet=-1|OwnerPartId=-1|Location.X=170|Location.Y=970|Color=128
|RECORD=29|IndexInSheet=-1|OwnerPartId=-1|Location.X=180|Location.Y=590|Color=128
|RECORD=29|IndexInSheet=-1|OwnerPartId=-1|Location.X=180|Location.Y=650|Color=128
|RECORD=29|IndexInSheet=-1|OwnerPartId=-1|Location.X=190|Location.Y=800|Color=128
|RECORD=29|IndexInSheet=-1|OwnerPartId=-1|Location.X=190|Location.Y=850|Color=128
|RECORD=29|IndexInSheet=-1|OwnerPartId=-1|Location.X=200|Location.Y=410|Color=128
|RECORD=29|IndexInSheet=-1|OwnerPartId=-1|Location.X=200|Location.Y=470|Color=128
|RECORD=29|IndexInSheet=-1|OwnerPartId=-1|Location.X=220|Location.Y=920|Color=128
|RECORD=29|IndexInSheet=-1|OwnerPartId=-1|Location.X=220|Location.Y=980|Color=128
|RECORD=29|IndexInSheet=-1|OwnerPartId=-1|Location.X=230|Location.Y=650|Color=128
|RECORD=29|IndexInSheet=-1|OwnerPartId=-1|Location.X=240|Location.Y=850|Color=128
|RECORD=29|IndexInSheet=-1|OwnerPartId=-1|Location.X=250|Location.Y=470|Color=128
|RECORD=29|IndexInSheet=-1|OwnerPartId=-1|Location.X=270|Location.Y=980|Color=128
|RECORD=29|IndexInSheet=-1|OwnerPartId=-1|Location.X=290|Location.Y=800|Color=128
|RECORD=29|IndexInSheet=-1|OwnerPartId=-1|Location.X=290|Location.Y=860|Color=128
|RECORD=29|IndexInSheet=-1|OwnerPartId=-1|Location.X=340|Location.Y=860|Color=128
|RECORD=29|IndexInSheet=-1|OwnerPartId=-1|Location.X=380|Location.Y=620|Color=128
|RECORD=29|IndexInSheet=-1|OwnerPartId=-1|Location.X=390|Location.Y=630|Color=128
|RECORD=29|IndexInSheet=-1|OwnerPartId=-1|Location.X=400|Location.Y=640|Color=128
|RECORD=29|IndexInSheet=-1|OwnerPartId=-1|Location.X=410|Location.Y=650|Color=128
|RECORD=29|IndexInSheet=-1|OwnerPartId=-1|Location.X=470|Location.Y=860|Color=128
|RECORD=29|IndexInSheet=-1|OwnerPartId=-1|Location.X=480|Location.Y=150|Color=128
|RECORD=29|IndexInSheet=-1|OwnerPartId=-1|Location.X=480|Location.Y=850|Color=128
|RECORD=29|IndexInSheet=-1|OwnerPartId=-1|Location.X=490|Location.Y=840|Color=128
|RECORD=29|IndexInSheet=-1|OwnerPartId=-1|Location.X=500|Location.Y=830|Color=128
|RECORD=29|IndexInSheet=-1|OwnerPartId=-1|Location.X=590|Location.Y=650|Color=128
|RECORD=29|IndexInSheet=-1|OwnerPartId=-1|Location.X=630|Location.Y=320|Color=128
|RECORD=29|IndexInSheet=-1|OwnerPartId=-1|Location.X=640|Location.Y=640|Color=128
|RECORD=29|IndexInSheet=-1|OwnerPartId=-1|Location.X=650|Location.Y=630|Color=128
|RECORD=29|IndexInSheet=-1|OwnerPartId=-1|Location.X=660|Location.Y=100|Color=128
|RECORD=29|IndexInSheet=-1|OwnerPartId=-1|Location.X=660|Location.Y=620|Color=128
|RECORD=29|IndexInSheet=-1|OwnerPartId=-1|Location.X=680|Location.Y=310|Color=128
|RECORD=29|IndexInSheet=-1|OwnerPartId=-1|Location.X=710|Location.Y=860|Color=128
|RECORD=29|IndexInSheet=-1|OwnerPartId=-1|Location.X=750|Location.Y=850|Color=128
|RECORD=29|IndexInSheet=-1|OwnerPartId=-1|Location.X=760|Location.Y=840|Color=128
|RECORD=29|IndexInSheet=-1|OwnerPartId=-1|Location.X=770|Location.Y=830|Color=128
|RECORD=29|IndexInSheet=-1|OwnerPartId=-1|Location.X=890|Location.Y=260|Color=128
|RECORD=29|IndexInSheet=-1|OwnerPartId=-1|Location.X=1010|Location.Y=640|Color=128
|RECORD=29|IndexInSheet=-1|OwnerPartId=-1|Location.X=1010|Location.Y=710|Color=128
|RECORD=29|IndexInSheet=-1|OwnerPartId=-1|Location.X=1050|Location.Y=710|Color=128
|RECORD=29|IndexInSheet=-1|OwnerPartId=-1|Location.X=1070|Location.Y=710|Color=128
|RECORD=29|IndexInSheet=-1|OwnerPartId=-1|Location.X=1120|Location.Y=400|Color=128
|RECORD=29|IndexInSheet=-1|OwnerPartId=-1|Location.X=1160|Location.Y=270|Color=128
|RECORD=29|IndexInSheet=-1|OwnerPartId=-1|Location.X=1160|Location.Y=360|Color=128
|RECORD=29|IndexInSheet=-1|OwnerPartId=-1|Location.X=1160|Location.Y=390|Color=128
|RECORD=29|IndexInSheet=-1|OwnerPartId=-1|Location.X=1200|Location.Y=300|Color=128
|RECORD=29|IndexInSheet=-1|OwnerPartId=-1|Location.X=1210|Location.Y=140|Color=128
|RECORD=29|IndexInSheet=-1|OwnerPartId=-1|Location.X=1210|Location.Y=630|Color=128
|RECORD=29|IndexInSheet=-1|OwnerPartId=-1|Location.X=1210|Location.Y=640|Color=128
|RECORD=29|IndexInSheet=-1|OwnerPartId=-1|Location.X=1220|Location.Y=710|Color=128
|RECORD=29|IndexInSheet=-1|OwnerPartId=-1|Location.X=1235|Location.Y=630|Color=128
|RECORD=29|IndexInSheet=-1|OwnerPartId=-1|Location.X=1235|Location.Y=710|Color=128
|RECORD=29|IndexInSheet=-1|OwnerPartId=-1|Location.X=1240|Location.Y=710|Color=128
|RECORD=29|IndexInSheet=-1|OwnerPartId=-1|Location.X=1280|Location.Y=630|Color=128
|RECORD=29|IndexInSheet=-1|OwnerPartId=-1|Location.X=1280|Location.Y=710|Color=128
|RECORD=29|IndexInSheet=-1|OwnerPartId=-1|Location.X=1290|Location.Y=350|Color=128
|RECORD=29|IndexInSheet=-1|OwnerPartId=-1|Location.X=1325|Location.Y=630|Color=128
|RECORD=29|IndexInSheet=-1|OwnerPartId=-1|Location.X=1325|Location.Y=710|Color=128
|RECORD=29|IndexInSheet=-1|OwnerPartId=-1|Location.X=1340|Location.Y=510|Color=128
|RECORD=29|IndexInSheet=-1|OwnerPartId=-1|Location.X=1340|Location.Y=540|Color=128
|RECORD=29|IndexInSheet=-1|OwnerPartId=-1|Location.X=1360|Location.Y=770|Color=128
|RECORD=29|IndexInSheet=-1|OwnerPartId=-1|Location.X=1410|Location.Y=810|Color=128
|RECORD=29|IndexInSheet=-1|OwnerPartId=-1|Location.X=1420|Location.Y=500|Color=128
|RECORD=29|IndexInSheet=-1|OwnerPartId=-1|Location.X=1420|Location.Y=510|Color=128
|RECORD=29|IndexInSheet=-1|OwnerPartId=-1|Location.X=1420|Location.Y=540|Color=128
|RECORD=29|IndexInSheet=-1|OwnerPartId=-1|Location.X=1510|Location.Y=190|Color=128
|RECORD=29|IndexInSheet=-1|OwnerPartId=-1|Location.X=1600|Location.Y=300|Color=128
|RECORD=29|IndexInSheet=-1|OwnerPartId=-1|Location.X=1640|Location.Y=290|Color=128
|RECORD=29|IndexInSheet=-1|OwnerPartId=-1|Location.X=1640|Location.Y=430|Color=128
|RECORD=29|IndexInSheet=-1|OwnerPartId=-1|Location.X=1640|Location.Y=460|Color=128